FILE_TYPE = MACRO_DRAWING;
SET COLOR_WIRE YELLOW;
SET COLOR_PROP MONO;
SET COLOR_DOT WHITE;
SET COLOR_ARC YELLOW;
SET COLOR_BODY GREEN;
SET COLOR_NOTE MONO;
SET PROP_DISPLAY VALUE;
SET PAGE_NUMBER P95;
FORCEADD GND..1
(-3100 425);
FORCEPROP 3 LASTPIN (-3100 475) SIG_NAME GND\g
J 0
(-3090 485);
DISPLAY 0.659574 (-3090 485);
PAINT MONO (-3090 485);
DISPLAY INVISIBLE (-3090 485);
FORCEPROP 1 LAST HDL_POWER GND
J 0
(-3100 575);
DISPLAY 1.170213 (-3100 575);
PAINT GREEN (-3100 575);
DISPLAY INVISIBLE (-3100 575);
FORCEPROP 1 LAST PATH I1
J 0
(-3025 425);
DISPLAY 0.872340 (-3025 425);
PAINT AQUA (-3025 425);
DISPLAY INVISIBLE (-3025 425);
FORCEPROP 1 LAST BODY_TYPE PLUMBING
J 0
(-3145 382);
DISPLAY 0.340426 (-3145 382);
PAINT GREEN (-3145 382);
DISPLAY INVISIBLE (-3145 382);
FORCEPROP 1 LAST SIZE 1B
J 0
(-3025 375);
DISPLAY 1.170213 (-3025 375);
PAINT GREEN (-3025 375);
DISPLAY INVISIBLE (-3025 375);
FORCEPROP 2 LAST CDS_LIB mstr_symbols
J 1
(-3100 425);
PAINT ORANGE (-3100 425);
DISPLAY INVISIBLE (-3100 425);
FORCEPROP 1 LAST VOLTAGE 0
J 0
(-3100 425);
PAINT SKYBLUE (-3100 425);
DISPLAY INVISIBLE (-3100 425);
FORCEADD GND..1
(2150 950);
FORCEPROP 3 LASTPIN (2150 1000) SIG_NAME GND\g
J 0
(2160 1010);
DISPLAY 0.659574 (2160 1010);
PAINT MONO (2160 1010);
DISPLAY INVISIBLE (2160 1010);
FORCEPROP 1 LAST HDL_POWER GND
J 0
(2150 1100);
DISPLAY 1.170213 (2150 1100);
PAINT GREEN (2150 1100);
DISPLAY INVISIBLE (2150 1100);
FORCEPROP 2 LAST ROOM PROCHOT_MEMHOT_ISO
J 0
(1775 1025);
PAINT ORANGE (1775 1025);
DISPLAY INVISIBLE (1775 1025);
FORCEPROP 1 LAST PATH I105
J 0
(2225 950);
DISPLAY 0.872340 (2225 950);
PAINT AQUA (2225 950);
DISPLAY INVISIBLE (2225 950);
FORCEPROP 1 LAST BODY_TYPE PLUMBING
J 0
(2105 907);
DISPLAY 0.340426 (2105 907);
PAINT GREEN (2105 907);
DISPLAY INVISIBLE (2105 907);
FORCEPROP 1 LAST SIZE 1B
J 0
(2225 900);
DISPLAY 1.170213 (2225 900);
PAINT GREEN (2225 900);
DISPLAY INVISIBLE (2225 900);
FORCEPROP 2 LAST CDS_LIB mstr_symbols
J 0
(2150 950);
PAINT MONO (2150 950);
DISPLAY INVISIBLE (2150 950);
FORCEPROP 1 LAST VOLTAGE 0.0V
J 0
(2105 907);
DISPLAY 0.340426 (2105 907);
PAINT SKYBLUE (2105 907);
DISPLAY INVISIBLE (2105 907);
FORCEADD RES..2
(2150 1800);
FORCEPROP 1 LAST PART_NUMBER G21796-072
J 0
(2190 1675);
DISPLAY 0.617021 (2190 1675);
PAINT BLUE (2190 1675);
FORCEPROP 1 LAST WATTAGE 1/16W
J 0
(2190 1775);
DISPLAY 0.617021 (2190 1775);
PAINT SKYBLUE (2190 1775);
FORCEPROP 1 LAST VALUE 4.75K
J 0
(2195 1875);
DISPLAY 0.617021 (2195 1875);
PAINT SKYBLUE (2195 1875);
FORCEPROP 1 LASTPIN (2150 1900) $PN 1
J 0
(2155 1862);
DISPLAY 0.617021 (2155 1862);
PAINT ORANGE (2155 1862);
FORCEPROP 1 LASTPIN (2150 1700) $PN 2
J 0
(2155 1710);
DISPLAY 0.617021 (2155 1710);
PAINT ORANGE (2155 1710);
FORCEPROP 1 LAST MATERIAL CHIP
J 0
(2190 1725);
DISPLAY 0.617021 (2190 1725);
PAINT SKYBLUE (2190 1725);
FORCEPROP 1 LAST PACK_TYPE 0402
J 0
(2190 1625);
DISPLAY 0.617021 (2190 1625);
PAINT SKYBLUE (2190 1625);
FORCEPROP 1 LAST TOLERANCE 1%
J 0
(2195 1825);
DISPLAY 0.617021 (2195 1825);
PAINT SKYBLUE (2195 1825);
FORCEPROP 1 LAST LOCATION R7E7
J 0
(2195 1925);
DISPLAY 0.617021 (2195 1925);
PAINT AQUA (2195 1925);
FORCEPROP 0 LAST ROOM PROC_SIDEBAND
J 0
(2200 2025);
DISPLAY 1.021277 (2200 2025);
PAINT ORANGE (2200 2025);
DISPLAY INVISIBLE (2200 2025);
FORCEPROP 1 LAST PATH I106
J 0
(2200 1975);
DISPLAY 0.978723 (2200 1975);
PAINT WHITE (2200 1975);
DISPLAY INVISIBLE (2200 1975);
FORCEPROP 2 LAST CDS_LOCATION R7E7
J 0
(2195 1925);
DISPLAY 0.617021 (2195 1925);
PAINT AQUA (2195 1925);
DISPLAY INVISIBLE (2195 1925);
FORCEPROP 2 LAST SEC 1
J 0
(2200 2025);
DISPLAY 0.680851 (2200 2025);
PAINT MONO (2200 2025);
DISPLAY INVISIBLE (2200 2025);
FORCEPROP 2 LAST SEC_TYPE 0402
J 0
(2200 2025);
DISPLAY 1.021277 (2200 2025);
PAINT ORANGE (2200 2025);
DISPLAY INVISIBLE (2200 2025);
FORCEPROP 2 LAST CDS_LIB mstr_discrete
J 0
(2150 1800);
PAINT MONO (2150 1800);
DISPLAY INVISIBLE (2150 1800);
FORCEADD P3V3..1
(2150 2075);
FORCEPROP 3 LASTPIN (2150 2025) SIG_NAME P3V3\g
J 0
(2160 2035);
DISPLAY 0.659574 (2160 2035);
PAINT MONO (2160 2035);
DISPLAY INVISIBLE (2160 2035);
FORCEPROP 1 LAST HDL_POWER P3V3
J 0
(1825 1950);
DISPLAY 1.170213 (1825 1950);
PAINT GREEN (1825 1950);
DISPLAY INVISIBLE (1825 1950);
FORCEPROP 2 LAST ROOM PROCHOT_MEMHOT_ISO
J 0
(1950 2175);
DISPLAY 1.340426 (1950 2175);
PAINT ORANGE (1950 2175);
DISPLAY INVISIBLE (1950 2175);
FORCEPROP 1 LAST PATH I107
J 0
(2195 2077);
DISPLAY 0.340426 (2195 2077);
PAINT GREEN (2195 2077);
DISPLAY INVISIBLE (2195 2077);
FORCEPROP 1 LAST BODY_TYPE PLUMBING
J 0
(2105 2032);
DISPLAY 0.446809 (2105 2032);
PAINT GREEN (2105 2032);
DISPLAY INVISIBLE (2105 2032);
FORCEPROP 1 LAST SIZE 1B
J 0
(2195 2097);
DISPLAY 0.446809 (2195 2097);
PAINT GREEN (2195 2097);
DISPLAY INVISIBLE (2195 2097);
FORCEPROP 2 LAST CDS_LIB mstr_symbols
J 0
(2150 2075);
PAINT MONO (2150 2075);
DISPLAY INVISIBLE (2150 2075);
FORCEPROP 1 LAST VOLTAGE 3.3V
J 0
(2105 2032);
DISPLAY 0.340426 (2105 2032);
PAINT SKYBLUE (2105 2032);
DISPLAY INVISIBLE (2105 2032);
FORCEADD RES..1
(1325 1250);
FORCEPROP 1 LAST PACK_TYPE 0402
J 0
(1150 1100);
DISPLAY 0.617021 (1150 1100);
PAINT SKYBLUE (1150 1100);
FORCEPROP 1 LAST PART_NUMBER G21497-005
J 0
(1150 1150);
DISPLAY 0.617021 (1150 1150);
PAINT BLUE (1150 1150);
FORCEPROP 1 LAST MATERIAL CHIP
J 0
(1300 1200);
DISPLAY 0.617021 (1300 1200);
PAINT SKYBLUE (1300 1200);
FORCEPROP 1 LAST WATTAGE 1/16W
J 2
(1250 1200);
DISPLAY 0.617021 (1250 1200);
PAINT SKYBLUE (1250 1200);
FORCEPROP 1 LAST TOLERANCE 5%
J 0
(1425 1300);
DISPLAY 0.617021 (1425 1300);
PAINT SKYBLUE (1425 1300);
FORCEPROP 1 LASTPIN (1425 1250) $PN 2
J 0
(1387 1262);
DISPLAY 0.617021 (1387 1262);
PAINT ORANGE (1387 1262);
FORCEPROP 1 LAST VALUE 0.0
J 2
(1375 1300);
DISPLAY 0.617021 (1375 1300);
PAINT SKYBLUE (1375 1300);
FORCEPROP 1 LAST LOCATION R7E9
J 0
(1150 1300);
DISPLAY 0.617021 (1150 1300);
PAINT AQUA (1150 1300);
FORCEPROP 1 LASTPIN (1225 1250) $PN 1
J 0
(1237 1262);
DISPLAY 0.617021 (1237 1262);
PAINT ORANGE (1237 1262);
FORCEPROP 2 LAST ROOM PROC_SIDEBAND
J 0
(1250 1175);
DISPLAY 0.617021 (1250 1175);
PAINT ORANGE (1250 1175);
DISPLAY INVISIBLE (1250 1175);
FORCEPROP 1 LAST PATH I108
J 0
(1275 1400);
DISPLAY 0.978723 (1275 1400);
PAINT WHITE (1275 1400);
DISPLAY INVISIBLE (1275 1400);
FORCEPROP 2 LAST CDS_LOCATION R7E9
J 0
(1275 1300);
DISPLAY 0.617021 (1275 1300);
PAINT AQUA (1275 1300);
DISPLAY INVISIBLE (1275 1300);
FORCEPROP 2 LAST SEC 1
J 0
(1275 1450);
DISPLAY 0.680851 (1275 1450);
PAINT MONO (1275 1450);
DISPLAY INVISIBLE (1275 1450);
FORCEPROP 2 LAST BOM_COST PROC_SIDEBAND
J 2
(1325 1250);
PAINT MONO (1325 1250);
DISPLAY INVISIBLE (1325 1250);
FORCEPROP 2 LAST CDS_LIB mstr_discrete
J 0
(1325 1250);
PAINT MONO (1325 1250);
DISPLAY INVISIBLE (1325 1250);
FORCEPROP 2 LAST SEC_TYPE 0402
J 0
(1275 1450);
DISPLAY 1.021277 (1275 1450);
PAINT ORANGE (1275 1450);
DISPLAY INVISIBLE (1275 1450);
FORCEADD OFFPAGE..1
(700 1250);
FORCEPROP 2 LAST $XR3 146 
J 0
(88 1250);
DISPLAY 0.638298 (88 1250);
PAINT MONO (88 1250);
FORCEPROP 2 LAST $XR2 170 
J 0
(208 1250);
DISPLAY 0.638298 (208 1250);
PAINT MONO (208 1250);
FORCEPROP 2 LAST $XR1 133 
J 0
(328 1250);
DISPLAY 0.638298 (328 1250);
PAINT MONO (328 1250);
FORCEPROP 2 LAST $XR0 119 
J 0
(448 1250);
DISPLAY 0.638298 (448 1250);
PAINT MONO (448 1250);
FORCEPROP 2 LAST PATH I109
J 0
(750 1325);
DISPLAY 1.021277 (750 1325);
PAINT ORANGE (750 1325);
DISPLAY INVISIBLE (750 1325);
FORCEPROP 1 LAST COMMENT_BODY TRUE
J 0
(825 1150);
DISPLAY 0.978723 (825 1150);
PAINT PEACH (825 1150);
DISPLAY INVISIBLE (825 1150);
FORCEPROP 1 LAST OFFPAGE TRUE
J 0
(1025 1125);
DISPLAY 0.978723 (1025 1125);
PAINT GREEN (1025 1125);
DISPLAY INVISIBLE (1025 1125);
FORCEPROP 2 LAST ROOM PROCHOT_MEMHOT_ISO
J 0
(450 1300);
DISPLAY 0.978723 (450 1300);
PAINT ORANGE (450 1300);
DISPLAY INVISIBLE (450 1300);
FORCEPROP 2 LAST CDS_LIB mstr_standard
J 0
(700 1250);
PAINT MONO (700 1250);
DISPLAY INVISIBLE (700 1250);
FORCEADD OFFPAGE..5
R 2
(3255 1600);
FORCEPROP 2 LAST $XR0 95 
J 0
(3444 1600);
DISPLAY 0.638298 (3444 1600);
PAINT MONO (3444 1600);
FORCEPROP 2 LAST PATH I110
J 0
(3425 1675);
DISPLAY 1.021277 (3425 1675);
PAINT ORANGE (3425 1675);
DISPLAY INVISIBLE (3425 1675);
FORCEPROP 1 LAST COMMENT_BODY TRUE
J 2
(3155 1525);
DISPLAY 0.978723 (3155 1525);
PAINT GREEN (3155 1525);
DISPLAY INVISIBLE (3155 1525);
FORCEPROP 1 LAST OFFPAGE TRUE
J 2
(2930 1475);
DISPLAY 0.978723 (2930 1475);
PAINT GREEN (2930 1475);
DISPLAY INVISIBLE (2930 1475);
FORCEPROP 2 LAST CDS_LIB mstr_standard
J 0
(3255 1600);
PAINT MONO (3255 1600);
DISPLAY INVISIBLE (3255 1600);
FORCEADD FET_N_DUAL..5
(2475 4325);
FORCEPROP 1 LAST VALUE NTJD4001N
J 0
(2675 4275);
DISPLAY 0.617021 (2675 4275);
PAINT SKYBLUE (2675 4275);
FORCEPROP 1 LAST MATERIAL FET
J 0
(2675 4225);
DISPLAY 0.617021 (2675 4225);
PAINT SKYBLUE (2675 4225);
FORCEPROP 1 LAST PART_NUMBER E40049-001
J 0
(2675 4125);
DISPLAY 0.617021 (2675 4125);
PAINT BLUE (2675 4125);
FORCEPROP 1 LASTPIN (2475 4525) $PN 6
J 2
(2528 4490);
DISPLAY 0.617021 (2528 4490);
PAINT WHITE (2528 4490);
FORCEPROP 1 LASTPIN (2275 4225) $PN 2
J 2
(2278 4240);
DISPLAY 0.617021 (2278 4240);
PAINT WHITE (2278 4240);
FORCEPROP 1 LASTPIN (2475 4125) $PN 1
J 2
(2533 4125);
DISPLAY 0.617021 (2533 4125);
PAINT WHITE (2533 4125);
FORCEPROP 1 LAST LOCATION Q7E5
J 0
(2675 4325);
DISPLAY 0.617021 (2675 4325);
PAINT AQUA (2675 4325);
FORCEPROP 2 LAST ROOM HOT_EVENTS
J 0
(2675 4425);
PAINT ORANGE (2675 4425);
DISPLAY INVISIBLE (2675 4425);
FORCEPROP 1 LAST PATH I111
J 0
(2675 4375);
DISPLAY 0.978723 (2675 4375);
PAINT BLUE (2675 4375);
DISPLAY INVISIBLE (2675 4375);
FORCEPROP 2 LAST CDS_LOCATION Q7E5
J 0
(2675 4325);
DISPLAY 0.617021 (2675 4325);
PAINT AQUA (2675 4325);
DISPLAY INVISIBLE (2675 4325);
FORCEPROP 2 LAST SEC 1
J 0
(2675 4425);
DISPLAY 0.680851 (2675 4425);
PAINT MONO (2675 4425);
DISPLAY INVISIBLE (2675 4425);
FORCEPROP 2 LAST BOM_COST PROC_SIDEBAND
J 0
(2475 4325);
PAINT MONO (2475 4325);
DISPLAY INVISIBLE (2475 4325);
FORCEPROP 2 LAST CDS_LIB mstr_discrete
J 0
(2475 4325);
PAINT MONO (2475 4325);
DISPLAY INVISIBLE (2475 4325);
FORCEPROP 2 LAST SEC_TYPE SMLF
J 0
(2675 4425);
DISPLAY 1.021277 (2675 4425);
PAINT ORANGE (2675 4425);
DISPLAY INVISIBLE (2675 4425);
FORCEPROP 1 LAST PACK_TYPE SMLF
J 0
(2675 4175);
DISPLAY 0.978723 (2675 4175);
PAINT SKYBLUE (2675 4175);
DISPLAY INVISIBLE (2675 4175);
FORCEADD FET_N_DUAL..5
(2550 2875);
FORCEPROP 1 LASTPIN (2550 3075) $PN 6
J 2
(2603 3040);
DISPLAY 0.617021 (2603 3040);
PAINT WHITE (2603 3040);
FORCEPROP 1 LASTPIN (2350 2775) $PN 2
J 2
(2353 2790);
DISPLAY 0.617021 (2353 2790);
PAINT WHITE (2353 2790);
FORCEPROP 1 LASTPIN (2550 2675) $PN 1
J 2
(2608 2675);
DISPLAY 0.617021 (2608 2675);
PAINT WHITE (2608 2675);
FORCEPROP 1 LAST MATERIAL FET
J 0
(2750 2775);
DISPLAY 0.617021 (2750 2775);
PAINT SKYBLUE (2750 2775);
FORCEPROP 1 LAST VALUE NTJD4001N
J 0
(2750 2825);
DISPLAY 0.617021 (2750 2825);
PAINT SKYBLUE (2750 2825);
FORCEPROP 1 LAST PART_NUMBER E40049-001
J 0
(2750 2675);
DISPLAY 0.617021 (2750 2675);
PAINT BLUE (2750 2675);
FORCEPROP 1 LAST LOCATION Q7E6
J 0
(2750 2875);
DISPLAY 0.617021 (2750 2875);
PAINT AQUA (2750 2875);
FORCEPROP 2 LAST ROOM HOT_EVENTS
J 0
(2750 2975);
PAINT ORANGE (2750 2975);
DISPLAY INVISIBLE (2750 2975);
FORCEPROP 1 LAST PATH I112
J 0
(2750 2925);
DISPLAY 0.978723 (2750 2925);
PAINT BLUE (2750 2925);
DISPLAY INVISIBLE (2750 2925);
FORCEPROP 2 LAST CDS_LOCATION Q7E6
J 0
(2750 2875);
DISPLAY 0.617021 (2750 2875);
PAINT AQUA (2750 2875);
DISPLAY INVISIBLE (2750 2875);
FORCEPROP 2 LAST SEC 1
J 0
(2750 2975);
DISPLAY 0.680851 (2750 2975);
PAINT MONO (2750 2975);
DISPLAY INVISIBLE (2750 2975);
FORCEPROP 2 LAST CDS_LIB mstr_discrete
J 0
(2550 2875);
PAINT MONO (2550 2875);
DISPLAY INVISIBLE (2550 2875);
FORCEPROP 2 LAST BOM_COST PROC_SIDEBAND
J 0
(2550 2875);
PAINT MONO (2550 2875);
DISPLAY INVISIBLE (2550 2875);
FORCEPROP 2 LAST SEC_TYPE SMLF
J 0
(2750 2975);
DISPLAY 1.021277 (2750 2975);
PAINT ORANGE (2750 2975);
DISPLAY INVISIBLE (2750 2975);
FORCEPROP 1 LAST PACK_TYPE SMLF
J 0
(2750 2725);
DISPLAY 0.978723 (2750 2725);
PAINT SKYBLUE (2750 2725);
DISPLAY INVISIBLE (2750 2725);
FORCEADD FET_N_DUAL..5
(-3100 1950);
FORCEPROP 1 LASTPIN (-3100 2150) $PN 3
J 2
(-3047 2115);
DISPLAY 0.617021 (-3047 2115);
PAINT WHITE (-3047 2115);
FORCEPROP 1 LASTPIN (-3300 1850) $PN 5
J 2
(-3297 1865);
DISPLAY 0.617021 (-3297 1865);
PAINT WHITE (-3297 1865);
FORCEPROP 1 LASTPIN (-3100 1750) $PN 4
J 2
(-3042 1750);
DISPLAY 0.617021 (-3042 1750);
PAINT WHITE (-3042 1750);
FORCEPROP 1 LAST MATERIAL FET
J 0
(-2900 2000);
DISPLAY 0.617021 (-2900 2000);
PAINT SKYBLUE (-2900 2000);
FORCEPROP 1 LAST VALUE NTJD4001N
J 0
(-2900 2050);
DISPLAY 0.617021 (-2900 2050);
PAINT SKYBLUE (-2900 2050);
FORCEPROP 1 LAST PART_NUMBER E40049-001
J 0
(-2900 1950);
DISPLAY 0.617021 (-2900 1950);
PAINT BLUE (-2900 1950);
FORCEPROP 1 LAST LOCATION Q2U1
J 0
(-2900 2100);
DISPLAY 0.617021 (-2900 2100);
PAINT AQUA (-2900 2100);
FORCEPROP 2 LAST ROOM PROC_SIDEBAND
J 1
(-2900 2200);
PAINT ORANGE (-2900 2200);
DISPLAY INVISIBLE (-2900 2200);
FORCEPROP 1 LAST PATH I113
J 0
(-2900 2000);
DISPLAY 0.978723 (-2900 2000);
PAINT BLUE (-2900 2000);
DISPLAY INVISIBLE (-2900 2000);
FORCEPROP 2 LAST CDS_LOCATION Q2U1
J 0
(-2900 2100);
DISPLAY 0.617021 (-2900 2100);
PAINT AQUA (-2900 2100);
DISPLAY INVISIBLE (-2900 2100);
FORCEPROP 2 LAST SEC 2
J 0
(-2900 2150);
DISPLAY 0.680851 (-2900 2150);
PAINT MONO (-2900 2150);
DISPLAY INVISIBLE (-2900 2150);
FORCEPROP 2 LAST BOM_COST PROC_SIDEBAND
J 0
(-3100 1950);
PAINT MONO (-3100 1950);
DISPLAY INVISIBLE (-3100 1950);
FORCEPROP 2 LAST CDS_LIB mstr_discrete
J 0
(-3100 1950);
PAINT ORANGE (-3100 1950);
DISPLAY INVISIBLE (-3100 1950);
FORCEPROP 2 LAST SEC_TYPE SMLF
J 0
(-2900 2150);
DISPLAY 1.021277 (-2900 2150);
PAINT ORANGE (-2900 2150);
DISPLAY INVISIBLE (-2900 2150);
FORCEPROP 1 LAST PACK_TYPE SMLF
J 0
(-2900 1800);
PAINT SKYBLUE (-2900 1800);
DISPLAY INVISIBLE (-2900 1800);
FORCEADD P3V3_STBY..1
(1125 3675);
FORCEPROP 3 LASTPIN (1125 3625) SIG_NAME P3V3_STBY\g
J 0
(1135 3635);
DISPLAY 0.659574 (1135 3635);
PAINT MONO (1135 3635);
DISPLAY INVISIBLE (1135 3635);
FORCEPROP 1 LAST HDL_POWER P3V3_STBY
J 0
(825 3550);
DISPLAY 0.872340 (825 3550);
PAINT ORANGE (825 3550);
DISPLAY INVISIBLE (825 3550);
FORCEPROP 1 LAST PATH I114
J 0
(1170 3677);
DISPLAY 0.340426 (1170 3677);
PAINT GREEN (1170 3677);
DISPLAY INVISIBLE (1170 3677);
FORCEPROP 1 LAST BODY_TYPE PLUMBING
J 0
(1080 3632);
DISPLAY 0.340426 (1080 3632);
PAINT GREEN (1080 3632);
DISPLAY INVISIBLE (1080 3632);
FORCEPROP 2 LAST CDS_LIB mstr_symbols
J 0
(1125 3675);
PAINT ORANGE (1125 3675);
DISPLAY INVISIBLE (1125 3675);
FORCEPROP 1 LAST SIZE 1B
J 0
(1170 3697);
DISPLAY 0.340426 (1170 3697);
PAINT GREEN (1170 3697);
DISPLAY INVISIBLE (1170 3697);
FORCEPROP 1 LAST VOLTAGE 3.3V
J 0
(1080 3632);
DISPLAY 0.340426 (1080 3632);
PAINT SKYBLUE (1080 3632);
DISPLAY INVISIBLE (1080 3632);
FORCEADD CAP_A..1
(1125 3450);
FORCEPROP 1 LASTPIN (1125 3350) $PN 2
J 0
(1135 3330);
DISPLAY 0.617021 (1135 3330);
PAINT ORANGE (1135 3330);
FORCEPROP 1 LASTPIN (1125 3550) $PN 1
J 0
(1135 3530);
DISPLAY 0.617021 (1135 3530);
PAINT ORANGE (1135 3530);
FORCEPROP 1 LAST PACK_TYPE 0402V
J 0
(1175 3250);
DISPLAY 0.617021 (1175 3250);
PAINT SKYBLUE (1175 3250);
FORCEPROP 1 LAST LOCATION C7E4
J 0
(1175 3550);
DISPLAY 0.617021 (1175 3550);
PAINT AQUA (1175 3550);
FORCEPROP 1 LAST VALUE 0.1UF
J 0
(1175 3500);
DISPLAY 0.617021 (1175 3500);
PAINT SKYBLUE (1175 3500);
FORCEPROP 1 LAST VOLTAGE 16V
J 0
(1175 3450);
DISPLAY 0.617021 (1175 3450);
PAINT SKYBLUE (1175 3450);
FORCEPROP 1 LAST TOLERANCE 10%
J 0
(1175 3400);
DISPLAY 0.617021 (1175 3400);
PAINT SKYBLUE (1175 3400);
FORCEPROP 1 LAST MATERIAL X7R
J 0
(1175 3350);
DISPLAY 0.617021 (1175 3350);
PAINT SKYBLUE (1175 3350);
FORCEPROP 1 LAST PART_NUMBER A36096-030
J 0
(1175 3300);
DISPLAY 0.617021 (1175 3300);
PAINT BLUE (1175 3300);
FORCEPROP 2 LAST SEC 1
J 0
(1175 3650);
DISPLAY 0.680851 (1175 3650);
PAINT MONO (1175 3650);
DISPLAY INVISIBLE (1175 3650);
FORCEPROP 2 LAST SEC_TYPE 0402V
J 0
(1175 3650);
DISPLAY 1.021277 (1175 3650);
PAINT ORANGE (1175 3650);
DISPLAY INVISIBLE (1175 3650);
FORCEPROP 2 LAST CDS_SEC 1
J 0
(1175 3600);
PAINT ORANGE (1175 3600);
DISPLAY INVISIBLE (1175 3600);
FORCEPROP 2 LAST CDS_LIB dev_discrete
J 0
(1125 3450);
PAINT ORANGE (1125 3450);
DISPLAY INVISIBLE (1125 3450);
FORCEPROP 2 LAST BOM_COST PROC_SIDEBAND
J 0
(1175 3650);
DISPLAY 1.021277 (1175 3650);
PAINT ORANGE (1175 3650);
DISPLAY INVISIBLE (1175 3650);
FORCEPROP 2 LAST CDS_LOCATION C7E4
J 0
(1175 3550);
DISPLAY 0.617021 (1175 3550);
PAINT AQUA (1175 3550);
DISPLAY INVISIBLE (1175 3550);
FORCEPROP 2 LAST ROOM PROC_SIDEBAND
J 0
(1175 3600);
DISPLAY 1.021277 (1175 3600);
PAINT ORANGE (1175 3600);
DISPLAY INVISIBLE (1175 3600);
FORCEPROP 1 LAST PATH I115
J 0
(1175 3600);
DISPLAY 0.978723 (1175 3600);
PAINT WHITE (1175 3600);
DISPLAY INVISIBLE (1175 3600);
FORCEADD GND..1
(1125 3200);
FORCEPROP 3 LASTPIN (1125 3250) SIG_NAME GND\g
J 0
(1135 3260);
DISPLAY 0.659574 (1135 3260);
PAINT MONO (1135 3260);
DISPLAY INVISIBLE (1135 3260);
FORCEPROP 1 LAST HDL_POWER GND
J 0
(1125 3350);
DISPLAY 0.872340 (1125 3350);
PAINT GREEN (1125 3350);
DISPLAY INVISIBLE (1125 3350);
FORCEPROP 1 LAST PATH I116
J 0
(1200 3200);
DISPLAY 0.872340 (1200 3200);
PAINT AQUA (1200 3200);
DISPLAY INVISIBLE (1200 3200);
FORCEPROP 1 LAST BODY_TYPE PLUMBING
J 0
(1080 3157);
DISPLAY 0.340426 (1080 3157);
PAINT GREEN (1080 3157);
DISPLAY INVISIBLE (1080 3157);
FORCEPROP 2 LAST CDS_LIB mstr_symbols
J 0
(1125 3200);
PAINT ORANGE (1125 3200);
DISPLAY INVISIBLE (1125 3200);
FORCEPROP 1 LAST SIZE 1B
J 0
(1200 3150);
DISPLAY 0.872340 (1200 3150);
PAINT AQUA (1200 3150);
DISPLAY INVISIBLE (1200 3150);
FORCEPROP 1 LAST VOLTAGE 0.0V
J 0
(1080 3157);
DISPLAY 0.340426 (1080 3157);
PAINT SKYBLUE (1080 3157);
DISPLAY INVISIBLE (1080 3157);
FORCEADD TTL1G08..1
(1550 4225);
FORCEPROP 2 LASTPIN (1400 4175) $PN 2
J 2
(1390 4185);
DISPLAY 0.617021 (1390 4185);
PAINT ORANGE (1390 4185);
FORCEPROP 2 LASTPIN (1700 4225) $PN 4
J 0
(1710 4235);
DISPLAY 0.617021 (1710 4235);
PAINT ORANGE (1710 4235);
FORCEPROP 1 LAST MATERIAL IC
J 1
(1525 4435);
DISPLAY 0.617021 (1525 4435);
PAINT SKYBLUE (1525 4435);
FORCEPROP 1 LAST PACK_TYPE SOTLF
J 1
(1525 4400);
DISPLAY 0.617021 (1525 4400);
PAINT SKYBLUE (1525 4400);
FORCEPROP 1 LAST VALUE NC7SZ08
J 1
(1550 4100);
DISPLAY 0.617021 (1550 4100);
PAINT SKYBLUE (1550 4100);
FORCEPROP 1 LAST LOCATION U7E2
J 1
(1525 4360);
DISPLAY 0.617021 (1525 4360);
PAINT AQUA (1525 4360);
FORCEPROP 1 LAST POWER_GROUP VCC=P3V3_STBY;GND=GND;
J 1
(1575 4050);
DISPLAY 0.617021 (1575 4050);
PAINT ORANGE (1575 4050);
FORCEPROP 1 LAST PART_NUMBER D10321-001
J 1
(1525 4325);
DISPLAY 0.617021 (1525 4325);
PAINT BLUE (1525 4325);
FORCEPROP 2 LASTPIN (1400 4275) $PN 1
J 2
(1390 4285);
DISPLAY 0.617021 (1390 4285);
PAINT ORANGE (1390 4285);
FORCEPROP 0 LAST ROOM CAT_ERR
J 0
(1525 4525);
DISPLAY 1.021277 (1525 4525);
PAINT ORANGE (1525 4525);
DISPLAY INVISIBLE (1525 4525);
FORCEPROP 1 LAST PATH I117
J 1
(1530 4490);
DISPLAY 0.702128 (1530 4490);
PAINT WHITE (1530 4490);
DISPLAY INVISIBLE (1530 4490);
FORCEPROP 2 LAST CDS_LOCATION U7E2
J 1
(1525 4360);
DISPLAY 0.617021 (1525 4360);
PAINT AQUA (1525 4360);
DISPLAY INVISIBLE (1525 4360);
FORCEPROP 2 LAST SEC 1
J 0
(1550 4525);
DISPLAY 0.680851 (1550 4525);
PAINT MONO (1550 4525);
DISPLAY INVISIBLE (1550 4525);
FORCEPROP 2 LAST CDS_LIB mstr_ttl
J 0
(1550 4225);
PAINT ORANGE (1550 4225);
DISPLAY INVISIBLE (1550 4225);
FORCEPROP 0 LAST BOM_COST PROC_SIDEBAND
J 0
(1525 4625);
DISPLAY 1.021277 (1525 4625);
PAINT ORANGE (1525 4625);
DISPLAY INVISIBLE (1525 4625);
FORCEPROP 2 LAST SEC_TYPE SOTLF
J 0
(1550 4525);
DISPLAY 1.021277 (1550 4525);
PAINT ORANGE (1550 4525);
DISPLAY INVISIBLE (1550 4525);
FORCEADD TTL1G08..1
(1575 2775);
FORCEPROP 2 LASTPIN (1425 2825) $PN 1
J 2
(1415 2835);
DISPLAY 0.617021 (1415 2835);
PAINT ORANGE (1415 2835);
FORCEPROP 2 LASTPIN (1425 2725) $PN 2
J 2
(1415 2735);
DISPLAY 0.617021 (1415 2735);
PAINT ORANGE (1415 2735);
FORCEPROP 2 LASTPIN (1725 2775) $PN 4
J 0
(1735 2785);
DISPLAY 0.617021 (1735 2785);
PAINT ORANGE (1735 2785);
FORCEPROP 1 LAST VALUE NC7SZ08
J 1
(1575 2650);
DISPLAY 0.617021 (1575 2650);
PAINT SKYBLUE (1575 2650);
FORCEPROP 1 LAST PART_NUMBER D10321-001
J 1
(1550 2875);
DISPLAY 0.617021 (1550 2875);
PAINT BLUE (1550 2875);
FORCEPROP 1 LAST LOCATION U7E3
J 1
(1550 2910);
DISPLAY 0.617021 (1550 2910);
PAINT AQUA (1550 2910);
FORCEPROP 1 LAST POWER_GROUP VCC=P3V3_STBY;GND=GND;
J 1
(1600 2600);
DISPLAY 0.617021 (1600 2600);
PAINT ORANGE (1600 2600);
FORCEPROP 1 LAST MATERIAL IC
J 1
(1550 2985);
DISPLAY 0.617021 (1550 2985);
PAINT SKYBLUE (1550 2985);
FORCEPROP 1 LAST PACK_TYPE SOTLF
J 1
(1550 2950);
DISPLAY 0.617021 (1550 2950);
PAINT SKYBLUE (1550 2950);
FORCEPROP 0 LAST ROOM CAT_ERR
J 0
(1550 3075);
DISPLAY 1.021277 (1550 3075);
PAINT ORANGE (1550 3075);
DISPLAY INVISIBLE (1550 3075);
FORCEPROP 1 LAST PATH I118
J 1
(1555 3040);
DISPLAY 0.702128 (1555 3040);
PAINT WHITE (1555 3040);
DISPLAY INVISIBLE (1555 3040);
FORCEPROP 2 LAST CDS_LOCATION U7E3
J 1
(1550 2910);
DISPLAY 0.617021 (1550 2910);
PAINT AQUA (1550 2910);
DISPLAY INVISIBLE (1550 2910);
FORCEPROP 2 LAST SEC 1
J 0
(1575 3075);
DISPLAY 0.680851 (1575 3075);
PAINT MONO (1575 3075);
DISPLAY INVISIBLE (1575 3075);
FORCEPROP 2 LAST SEC_TYPE SOTLF
J 0
(1575 3075);
DISPLAY 1.021277 (1575 3075);
PAINT ORANGE (1575 3075);
DISPLAY INVISIBLE (1575 3075);
FORCEPROP 2 LAST CDS_LIB mstr_ttl
J 0
(1575 2775);
PAINT ORANGE (1575 2775);
DISPLAY INVISIBLE (1575 2775);
FORCEPROP 0 LAST BOM_COST PROC_SIDEBAND
J 0
(1550 3175);
DISPLAY 1.021277 (1550 3175);
PAINT ORANGE (1550 3175);
DISPLAY INVISIBLE (1550 3175);
FORCEADD OFFPAGE..2
(-700 3525);
FORCEPROP 2 LAST $XR2 93 
J 0
(-331 3525);
DISPLAY 0.638298 (-331 3525);
PAINT MONO (-331 3525);
FORCEPROP 2 LAST $XR1 95 
J 0
(-421 3525);
DISPLAY 0.638298 (-421 3525);
PAINT MONO (-421 3525);
FORCEPROP 2 LAST $XR0 55 
J 0
(-511 3525);
DISPLAY 0.638298 (-511 3525);
PAINT MONO (-511 3525);
FORCEPROP 2 LAST PATH I12
J 0
(-225 3575);
DISPLAY 1.021277 (-225 3575);
PAINT ORANGE (-225 3575);
DISPLAY INVISIBLE (-225 3575);
FORCEPROP 1 LAST COMMENT_BODY TRUE
J 0
(-745 3430);
DISPLAY 1.170213 (-745 3430);
PAINT GREEN (-745 3430);
DISPLAY INVISIBLE (-745 3430);
FORCEPROP 1 LAST OFFPAGE TRUE
J 0
(-375 3400);
PAINT GREEN (-375 3400);
DISPLAY INVISIBLE (-375 3400);
FORCEPROP 2 LAST ROOM SMART_CLST
J 0
(-950 3600);
DISPLAY 1.361702 (-950 3600);
PAINT ORANGE (-950 3600);
DISPLAY INVISIBLE (-950 3600);
FORCEPROP 2 LAST CDS_LIB mstr_standard
J 0
(-700 3525);
PAINT ORANGE (-700 3525);
DISPLAY INVISIBLE (-700 3525);
FORCEADD GND..1
(-3100 4250);
FORCEPROP 3 LASTPIN (-3100 4300) SIG_NAME GND\g
J 0
(-3090 4310);
DISPLAY 0.659574 (-3090 4310);
PAINT MONO (-3090 4310);
DISPLAY INVISIBLE (-3090 4310);
FORCEPROP 1 LAST HDL_POWER GND
J 0
(-3100 4400);
DISPLAY 1.170213 (-3100 4400);
PAINT GREEN (-3100 4400);
DISPLAY INVISIBLE (-3100 4400);
FORCEPROP 1 LAST PATH I120
J 0
(-3025 4250);
DISPLAY 0.872340 (-3025 4250);
PAINT AQUA (-3025 4250);
DISPLAY INVISIBLE (-3025 4250);
FORCEPROP 1 LAST BODY_TYPE PLUMBING
J 0
(-3145 4207);
DISPLAY 0.340426 (-3145 4207);
PAINT GREEN (-3145 4207);
DISPLAY INVISIBLE (-3145 4207);
FORCEPROP 1 LAST SIZE 1B
J 0
(-3025 4200);
DISPLAY 1.170213 (-3025 4200);
PAINT GREEN (-3025 4200);
DISPLAY INVISIBLE (-3025 4200);
FORCEPROP 2 LAST CDS_LIB mstr_symbols
J 0
(-3100 4250);
PAINT ORANGE (-3100 4250);
DISPLAY INVISIBLE (-3100 4250);
FORCEPROP 1 LAST VOLTAGE 0
J 0
(-3100 4250);
PAINT SKYBLUE (-3100 4250);
DISPLAY INVISIBLE (-3100 4250);
FORCEADD OFFPAGE..2
(-700 4850);
FORCEPROP 2 LAST $XR1 108 
J 0
(-391 4850);
DISPLAY 0.638298 (-391 4850);
PAINT MONO (-391 4850);
FORCEPROP 2 LAST $XR0 147 
J 0
(-511 4850);
DISPLAY 0.638298 (-511 4850);
PAINT MONO (-511 4850);
FORCEPROP 2 LAST PATH I121
J 0
(-525 4925);
DISPLAY 1.021277 (-525 4925);
PAINT ORANGE (-525 4925);
DISPLAY INVISIBLE (-525 4925);
FORCEPROP 1 LAST COMMENT_BODY TRUE
J 0
(-745 4755);
DISPLAY 1.170213 (-745 4755);
PAINT GREEN (-745 4755);
DISPLAY INVISIBLE (-745 4755);
FORCEPROP 1 LAST OFFPAGE TRUE
J 0
(-375 4725);
PAINT GREEN (-375 4725);
DISPLAY INVISIBLE (-375 4725);
FORCEPROP 2 LAST ROOM SMART_CLST
J 0
(-950 4925);
DISPLAY 1.361702 (-950 4925);
PAINT ORANGE (-950 4925);
DISPLAY INVISIBLE (-950 4925);
FORCEPROP 2 LAST CDS_LIB mstr_standard
J 0
(-700 4850);
PAINT ORANGE (-700 4850);
DISPLAY INVISIBLE (-700 4850);
FORCEADD FET_N..8
(2150 1350);
FORCEPROP 1 LAST LOCATION Q7E4
J 0
(2350 1350);
DISPLAY 0.617021 (2350 1350);
PAINT AQUA (2350 1350);
FORCEPROP 1 LAST MATERIAL FET
J 0
(2350 1250);
DISPLAY 0.617021 (2350 1250);
PAINT SKYBLUE (2350 1250);
FORCEPROP 1 LAST VALUE 2N7002
J 0
(2350 1300);
DISPLAY 0.617021 (2350 1300);
PAINT SKYBLUE (2350 1300);
FORCEPROP 1 LAST PART_NUMBER C79254-001
J 0
(2350 1150);
DISPLAY 0.617021 (2350 1150);
PAINT BLUE (2350 1150);
FORCEPROP 1 LASTPIN (1950 1250) $PN 1
J 2
(1953 1265);
DISPLAY 0.872340 (1953 1265);
PAINT WHITE (1953 1265);
DISPLAY INVISIBLE (1953 1265);
FORCEPROP 1 LASTPIN (2150 1550) $PN 3
J 2
(2203 1515);
DISPLAY 0.872340 (2203 1515);
PAINT WHITE (2203 1515);
DISPLAY INVISIBLE (2203 1515);
FORCEPROP 1 LASTPIN (2150 1150) $PN 2
J 2
(2208 1150);
DISPLAY 0.872340 (2208 1150);
PAINT WHITE (2208 1150);
DISPLAY INVISIBLE (2208 1150);
FORCEPROP 2 LAST CDS_LIB mstr_discrete
J 0
(2150 1350);
PAINT MONO (2150 1350);
DISPLAY INVISIBLE (2150 1350);
FORCEPROP 1 LAST PATH I122
J 0
(2350 1400);
DISPLAY 0.978723 (2350 1400);
PAINT BLUE (2350 1400);
DISPLAY INVISIBLE (2350 1400);
FORCEPROP 0 LAST ROOM HOT_SWAP
J 0
(2350 1450);
DISPLAY 1.021277 (2350 1450);
PAINT ORANGE (2350 1450);
DISPLAY INVISIBLE (2350 1450);
FORCEPROP 1 LAST PACK_TYPE SOT23LF
J 0
(2350 1200);
DISPLAY 0.978723 (2350 1200);
PAINT SKYBLUE (2350 1200);
DISPLAY INVISIBLE (2350 1200);
FORCEADD FET_N..8
(-3100 4550);
FORCEPROP 1 LAST PART_NUMBER C79254-001
J 0
(-2900 4350);
DISPLAY 0.617021 (-2900 4350);
PAINT BLUE (-2900 4350);
FORCEPROP 1 LAST VALUE 2N7002
J 0
(-2900 4500);
DISPLAY 0.617021 (-2900 4500);
PAINT SKYBLUE (-2900 4500);
FORCEPROP 1 LAST LOCATION Q7E8
J 0
(-2900 4550);
DISPLAY 0.617021 (-2900 4550);
PAINT AQUA (-2900 4550);
FORCEPROP 1 LAST MATERIAL FET
J 0
(-2900 4450);
DISPLAY 0.617021 (-2900 4450);
PAINT SKYBLUE (-2900 4450);
FORCEPROP 1 LASTPIN (-3300 4450) $PN 1
J 2
(-3297 4465);
DISPLAY 0.872340 (-3297 4465);
PAINT WHITE (-3297 4465);
DISPLAY INVISIBLE (-3297 4465);
FORCEPROP 1 LASTPIN (-3100 4750) $PN 3
J 2
(-3047 4715);
DISPLAY 0.872340 (-3047 4715);
PAINT WHITE (-3047 4715);
DISPLAY INVISIBLE (-3047 4715);
FORCEPROP 1 LASTPIN (-3100 4350) $PN 2
J 2
(-3042 4350);
DISPLAY 0.872340 (-3042 4350);
PAINT WHITE (-3042 4350);
DISPLAY INVISIBLE (-3042 4350);
FORCEPROP 1 LAST PACK_TYPE SOT23LF
J 0
(-2900 4400);
DISPLAY 0.978723 (-2900 4400);
PAINT SKYBLUE (-2900 4400);
DISPLAY INVISIBLE (-2900 4400);
FORCEPROP 0 LAST ROOM HOT_SWAP
J 0
(-2900 4650);
DISPLAY 1.021277 (-2900 4650);
PAINT ORANGE (-2900 4650);
DISPLAY INVISIBLE (-2900 4650);
FORCEPROP 1 LAST PATH I123
J 0
(-2900 4600);
DISPLAY 0.978723 (-2900 4600);
PAINT BLUE (-2900 4600);
DISPLAY INVISIBLE (-2900 4600);
FORCEPROP 2 LAST CDS_LIB mstr_discrete
J 0
(-3100 4550);
PAINT MONO (-3100 4550);
DISPLAY INVISIBLE (-3100 4550);
FORCEADD OFFPAGE..2
(-700 2850);
FORCEPROP 2 LAST $XR2 152 
J 0
(-331 2850);
DISPLAY 0.638298 (-331 2850);
PAINT MONO (-331 2850);
FORCEPROP 2 LAST $XR1 21 
J 0
(-421 2850);
DISPLAY 0.638298 (-421 2850);
PAINT MONO (-421 2850);
FORCEPROP 2 LAST $XR0 94 
J 0
(-511 2850);
DISPLAY 0.638298 (-511 2850);
PAINT MONO (-511 2850);
FORCEPROP 2 LAST PATH I13
J 0
(-400 2900);
DISPLAY 1.021277 (-400 2900);
PAINT ORANGE (-400 2900);
DISPLAY INVISIBLE (-400 2900);
FORCEPROP 1 LAST COMMENT_BODY TRUE
J 0
(-745 2755);
DISPLAY 1.170213 (-745 2755);
PAINT GREEN (-745 2755);
DISPLAY INVISIBLE (-745 2755);
FORCEPROP 1 LAST OFFPAGE TRUE
J 0
(-375 2725);
PAINT GREEN (-375 2725);
DISPLAY INVISIBLE (-375 2725);
FORCEPROP 2 LAST CDS_LIB mstr_standard
J 0
(-700 2850);
PAINT ORANGE (-700 2850);
DISPLAY INVISIBLE (-700 2850);
FORCEPROP 2 LAST ROOM SMART_CLST
J 0
(-950 2925);
DISPLAY 1.361702 (-950 2925);
PAINT ORANGE (-950 2925);
DISPLAY INVISIBLE (-950 2925);
FORCEADD OFFPAGE..2
(-675 2200);
FORCEPROP 2 LAST $XR2 152 
J 0
(-306 2200);
DISPLAY 0.638298 (-306 2200);
PAINT MONO (-306 2200);
FORCEPROP 2 LAST $XR1 21 
J 0
(-396 2200);
DISPLAY 0.638298 (-396 2200);
PAINT MONO (-396 2200);
FORCEPROP 2 LAST $XR0 94 
J 0
(-486 2200);
DISPLAY 0.638298 (-486 2200);
PAINT MONO (-486 2200);
FORCEPROP 2 LAST PATH I14
J 0
(-375 2250);
DISPLAY 1.021277 (-375 2250);
PAINT ORANGE (-375 2250);
DISPLAY INVISIBLE (-375 2250);
FORCEPROP 1 LAST COMMENT_BODY TRUE
J 0
(-720 2105);
DISPLAY 1.170213 (-720 2105);
PAINT GREEN (-720 2105);
DISPLAY INVISIBLE (-720 2105);
FORCEPROP 1 LAST OFFPAGE TRUE
J 0
(-350 2075);
PAINT GREEN (-350 2075);
DISPLAY INVISIBLE (-350 2075);
FORCEPROP 2 LAST CDS_LIB mstr_standard
J 0
(-675 2200);
PAINT ORANGE (-675 2200);
DISPLAY INVISIBLE (-675 2200);
FORCEPROP 2 LAST ROOM SMART_CLST
J 0
(-925 2275);
DISPLAY 1.361702 (-925 2275);
PAINT ORANGE (-925 2275);
DISPLAY INVISIBLE (-925 2275);
FORCEADD OFFPAGE..2
(-675 1550);
FORCEPROP 2 LAST $XR2 152 
J 0
(-306 1550);
DISPLAY 0.638298 (-306 1550);
PAINT MONO (-306 1550);
FORCEPROP 2 LAST $XR1 94 
J 0
(-396 1550);
DISPLAY 0.638298 (-396 1550);
PAINT MONO (-396 1550);
FORCEPROP 2 LAST $XR0 55 
J 0
(-486 1550);
DISPLAY 0.638298 (-486 1550);
PAINT MONO (-486 1550);
FORCEPROP 2 LAST PATH I18
J 0
(-375 1600);
DISPLAY 1.021277 (-375 1600);
PAINT ORANGE (-375 1600);
DISPLAY INVISIBLE (-375 1600);
FORCEPROP 1 LAST COMMENT_BODY TRUE
J 0
(-720 1455);
DISPLAY 1.170213 (-720 1455);
PAINT GREEN (-720 1455);
DISPLAY INVISIBLE (-720 1455);
FORCEPROP 1 LAST OFFPAGE TRUE
J 0
(-350 1425);
PAINT GREEN (-350 1425);
DISPLAY INVISIBLE (-350 1425);
FORCEPROP 2 LAST CDS_LIB mstr_standard
J 0
(-675 1550);
PAINT ORANGE (-675 1550);
DISPLAY INVISIBLE (-675 1550);
FORCEPROP 2 LAST ROOM PROC_SIDEBAND
J 0
(-925 1625);
DISPLAY 1.361702 (-925 1625);
PAINT ORANGE (-925 1625);
DISPLAY INVISIBLE (-925 1625);
FORCEADD OFFPAGE..2
(-675 925);
FORCEPROP 2 LAST $XR2 152 
J 0
(-306 925);
DISPLAY 0.638298 (-306 925);
PAINT MONO (-306 925);
FORCEPROP 2 LAST $XR1 94 
J 0
(-396 925);
DISPLAY 0.638298 (-396 925);
PAINT MONO (-396 925);
FORCEPROP 2 LAST $XR0 55 
J 0
(-486 925);
DISPLAY 0.638298 (-486 925);
PAINT MONO (-486 925);
FORCEPROP 2 LAST PATH I19
J 0
(-375 975);
DISPLAY 1.021277 (-375 975);
PAINT ORANGE (-375 975);
DISPLAY INVISIBLE (-375 975);
FORCEPROP 1 LAST COMMENT_BODY TRUE
J 0
(-720 830);
DISPLAY 1.170213 (-720 830);
PAINT GREEN (-720 830);
DISPLAY INVISIBLE (-720 830);
FORCEPROP 1 LAST OFFPAGE TRUE
J 0
(-350 800);
PAINT GREEN (-350 800);
DISPLAY INVISIBLE (-350 800);
FORCEPROP 2 LAST ROOM SMART_CLST
J 0
(-925 1000);
DISPLAY 1.361702 (-925 1000);
PAINT ORANGE (-925 1000);
DISPLAY INVISIBLE (-925 1000);
FORCEPROP 2 LAST CDS_LIB mstr_standard
J 0
(-675 925);
PAINT ORANGE (-675 925);
DISPLAY INVISIBLE (-675 925);
FORCEADD OFFPAGE..4
(-2475 5025);
FORCEPROP 2 LAST $XR0 95 
J 0
(-2289 5025);
DISPLAY 0.638298 (-2289 5025);
PAINT MONO (-2289 5025);
FORCEPROP 2 LAST PATH I22
J 0
(-2275 5075);
DISPLAY 1.021277 (-2275 5075);
PAINT ORANGE (-2275 5075);
DISPLAY INVISIBLE (-2275 5075);
FORCEPROP 1 LAST COMMENT_BODY TRUE
J 0
(-2500 4925);
DISPLAY 1.212766 (-2500 4925);
PAINT GREEN (-2500 4925);
DISPLAY INVISIBLE (-2500 4925);
FORCEPROP 1 LAST OFFPAGE TRUE
J 0
(-2150 4900);
PAINT GREEN (-2150 4900);
DISPLAY INVISIBLE (-2150 4900);
FORCEPROP 2 LAST CDS_LIB mstr_standard
J 0
(-2475 5025);
PAINT MONO (-2475 5025);
DISPLAY INVISIBLE (-2475 5025);
FORCEADD GND..1
(-3100 3675);
FORCEPROP 3 LASTPIN (-3100 3725) SIG_NAME GND\g
J 0
(-3090 3735);
DISPLAY 0.659574 (-3090 3735);
PAINT MONO (-3090 3735);
DISPLAY INVISIBLE (-3090 3735);
FORCEPROP 1 LAST HDL_POWER GND
J 0
(-3100 3825);
DISPLAY 1.170213 (-3100 3825);
PAINT GREEN (-3100 3825);
DISPLAY INVISIBLE (-3100 3825);
FORCEPROP 1 LAST PATH I23
J 0
(-3025 3675);
DISPLAY 0.872340 (-3025 3675);
PAINT AQUA (-3025 3675);
DISPLAY INVISIBLE (-3025 3675);
FORCEPROP 1 LAST BODY_TYPE PLUMBING
J 0
(-3145 3632);
DISPLAY 0.340426 (-3145 3632);
PAINT GREEN (-3145 3632);
DISPLAY INVISIBLE (-3145 3632);
FORCEPROP 2 LAST CDS_LIB mstr_symbols
J 1
(-3100 3675);
PAINT ORANGE (-3100 3675);
DISPLAY INVISIBLE (-3100 3675);
FORCEPROP 1 LAST SIZE 1B
J 0
(-3025 3625);
DISPLAY 1.170213 (-3025 3625);
PAINT GREEN (-3025 3625);
DISPLAY INVISIBLE (-3025 3625);
FORCEPROP 1 LAST VOLTAGE 0
J 0
(-3100 3675);
PAINT SKYBLUE (-3100 3675);
DISPLAY INVISIBLE (-3100 3675);
FORCEADD GND..1
(-3100 3000);
FORCEPROP 3 LASTPIN (-3100 3050) SIG_NAME GND\g
J 0
(-3090 3060);
DISPLAY 0.659574 (-3090 3060);
PAINT MONO (-3090 3060);
DISPLAY INVISIBLE (-3090 3060);
FORCEPROP 1 LAST HDL_POWER GND
J 0
(-3100 3150);
DISPLAY 1.170213 (-3100 3150);
PAINT GREEN (-3100 3150);
DISPLAY INVISIBLE (-3100 3150);
FORCEPROP 1 LAST PATH I26
J 0
(-3025 3000);
DISPLAY 0.872340 (-3025 3000);
PAINT AQUA (-3025 3000);
DISPLAY INVISIBLE (-3025 3000);
FORCEPROP 1 LAST BODY_TYPE PLUMBING
J 0
(-3145 2957);
DISPLAY 0.340426 (-3145 2957);
PAINT GREEN (-3145 2957);
DISPLAY INVISIBLE (-3145 2957);
FORCEPROP 1 LAST SIZE 1B
J 0
(-3025 2950);
DISPLAY 1.170213 (-3025 2950);
PAINT GREEN (-3025 2950);
DISPLAY INVISIBLE (-3025 2950);
FORCEPROP 2 LAST CDS_LIB mstr_symbols
J 1
(-3100 3000);
PAINT ORANGE (-3100 3000);
DISPLAY INVISIBLE (-3100 3000);
FORCEPROP 1 LAST VOLTAGE 0
J 0
(-3100 3000);
PAINT SKYBLUE (-3100 3000);
DISPLAY INVISIBLE (-3100 3000);
FORCEADD GND..1
(-3100 2350);
FORCEPROP 3 LASTPIN (-3100 2400) SIG_NAME GND\g
J 0
(-3090 2410);
DISPLAY 0.659574 (-3090 2410);
PAINT MONO (-3090 2410);
DISPLAY INVISIBLE (-3090 2410);
FORCEPROP 1 LAST HDL_POWER GND
J 0
(-3100 2500);
DISPLAY 0.936170 (-3100 2500);
PAINT GREEN (-3100 2500);
DISPLAY INVISIBLE (-3100 2500);
FORCEPROP 1 LAST PATH I27
J 0
(-3025 2350);
DISPLAY 0.872340 (-3025 2350);
PAINT AQUA (-3025 2350);
DISPLAY INVISIBLE (-3025 2350);
FORCEPROP 1 LAST BODY_TYPE PLUMBING
J 0
(-3145 2307);
DISPLAY 0.340426 (-3145 2307);
PAINT GREEN (-3145 2307);
DISPLAY INVISIBLE (-3145 2307);
FORCEPROP 1 LAST SIZE 1B
J 0
(-3025 2300);
DISPLAY 1.170213 (-3025 2300);
PAINT GREEN (-3025 2300);
DISPLAY INVISIBLE (-3025 2300);
FORCEPROP 2 LAST CDS_LIB mstr_symbols
J 1
(-3100 2350);
PAINT ORANGE (-3100 2350);
DISPLAY INVISIBLE (-3100 2350);
FORCEPROP 1 LAST VOLTAGE 0
J 0
(-3100 2350);
PAINT SKYBLUE (-3100 2350);
DISPLAY INVISIBLE (-3100 2350);
FORCEADD FET_N_DUAL..5
(-3100 2625);
FORCEPROP 1 LASTPIN (-3100 2825) $PN 6
J 2
(-3047 2790);
DISPLAY 0.617021 (-3047 2790);
PAINT MONO (-3047 2790);
FORCEPROP 1 LASTPIN (-3300 2525) $PN 2
J 2
(-3297 2540);
DISPLAY 0.617021 (-3297 2540);
PAINT MONO (-3297 2540);
FORCEPROP 1 LASTPIN (-3100 2425) $PN 1
J 2
(-3042 2425);
DISPLAY 0.617021 (-3042 2425);
PAINT MONO (-3042 2425);
FORCEPROP 1 LAST MATERIAL FET
J 0
(-2900 2675);
DISPLAY 0.617021 (-2900 2675);
PAINT SKYBLUE (-2900 2675);
FORCEPROP 1 LAST VALUE NTJD4001N
J 0
(-2900 2725);
DISPLAY 0.617021 (-2900 2725);
PAINT SKYBLUE (-2900 2725);
FORCEPROP 1 LAST PART_NUMBER E40049-001
J 0
(-2900 2625);
DISPLAY 0.617021 (-2900 2625);
PAINT BLUE (-2900 2625);
FORCEPROP 1 LAST LOCATION Q2U1
J 0
(-2900 2775);
DISPLAY 0.617021 (-2900 2775);
PAINT AQUA (-2900 2775);
FORCEPROP 2 LAST ROOM PROC_SIDEBAND
J 1
(-2900 2875);
PAINT ORANGE (-2900 2875);
DISPLAY INVISIBLE (-2900 2875);
FORCEPROP 1 LAST PATH I28
J 0
(-2900 2675);
DISPLAY 0.978723 (-2900 2675);
PAINT BLUE (-2900 2675);
DISPLAY INVISIBLE (-2900 2675);
FORCEPROP 2 LAST CDS_LOCATION Q2U1
J 0
(-2900 2775);
DISPLAY 0.617021 (-2900 2775);
PAINT AQUA (-2900 2775);
DISPLAY INVISIBLE (-2900 2775);
FORCEPROP 2 LAST SEC 1
J 1
(-2900 2725);
PAINT MONO (-2900 2725);
DISPLAY INVISIBLE (-2900 2725);
FORCEPROP 2 LAST CDS_LIB mstr_discrete
J 1
(-3100 2625);
PAINT ORANGE (-3100 2625);
DISPLAY INVISIBLE (-3100 2625);
FORCEPROP 2 LAST SEC_TYPE SMLF
J 1
(-2900 2725);
PAINT MONO (-2900 2725);
DISPLAY INVISIBLE (-2900 2725);
FORCEPROP 2 LAST BOM_COST PROC_SIDEBAND
J 0
(-3100 2625);
PAINT MONO (-3100 2625);
DISPLAY INVISIBLE (-3100 2625);
FORCEPROP 1 LAST PACK_TYPE SMLF
J 0
(-2900 2475);
PAINT SKYBLUE (-2900 2475);
DISPLAY INVISIBLE (-2900 2475);
FORCEADD GND..1
(-3100 1675);
FORCEPROP 3 LASTPIN (-3100 1725) SIG_NAME GND\g
J 0
(-3090 1735);
DISPLAY 0.659574 (-3090 1735);
PAINT MONO (-3090 1735);
DISPLAY INVISIBLE (-3090 1735);
FORCEPROP 1 LAST HDL_POWER GND
J 0
(-3100 1825);
DISPLAY 1.170213 (-3100 1825);
PAINT GREEN (-3100 1825);
DISPLAY INVISIBLE (-3100 1825);
FORCEPROP 1 LAST PATH I29
J 0
(-3025 1675);
DISPLAY 0.872340 (-3025 1675);
PAINT AQUA (-3025 1675);
DISPLAY INVISIBLE (-3025 1675);
FORCEPROP 1 LAST BODY_TYPE PLUMBING
J 0
(-3145 1632);
DISPLAY 0.340426 (-3145 1632);
PAINT GREEN (-3145 1632);
DISPLAY INVISIBLE (-3145 1632);
FORCEPROP 1 LAST SIZE 1B
J 0
(-3025 1625);
DISPLAY 1.170213 (-3025 1625);
PAINT GREEN (-3025 1625);
DISPLAY INVISIBLE (-3025 1625);
FORCEPROP 2 LAST CDS_LIB mstr_symbols
J 1
(-3100 1675);
PAINT ORANGE (-3100 1675);
DISPLAY INVISIBLE (-3100 1675);
FORCEPROP 1 LAST VOLTAGE 0
J 0
(-3100 1675);
PAINT SKYBLUE (-3100 1675);
DISPLAY INVISIBLE (-3100 1675);
FORCEADD GND..1
(-3100 1025);
FORCEPROP 3 LASTPIN (-3100 1075) SIG_NAME GND\g
J 0
(-3090 1085);
DISPLAY 0.659574 (-3090 1085);
PAINT MONO (-3090 1085);
DISPLAY INVISIBLE (-3090 1085);
FORCEPROP 1 LAST HDL_POWER GND
J 0
(-3100 1175);
DISPLAY 1.170213 (-3100 1175);
PAINT GREEN (-3100 1175);
DISPLAY INVISIBLE (-3100 1175);
FORCEPROP 1 LAST PATH I30
J 0
(-3025 1025);
DISPLAY 0.872340 (-3025 1025);
PAINT AQUA (-3025 1025);
DISPLAY INVISIBLE (-3025 1025);
FORCEPROP 1 LAST BODY_TYPE PLUMBING
J 0
(-3145 982);
DISPLAY 0.340426 (-3145 982);
PAINT GREEN (-3145 982);
DISPLAY INVISIBLE (-3145 982);
FORCEPROP 1 LAST SIZE 1B
J 0
(-3025 975);
DISPLAY 1.170213 (-3025 975);
PAINT GREEN (-3025 975);
DISPLAY INVISIBLE (-3025 975);
FORCEPROP 2 LAST CDS_LIB mstr_symbols
J 1
(-3100 1025);
PAINT ORANGE (-3100 1025);
DISPLAY INVISIBLE (-3100 1025);
FORCEPROP 1 LAST VOLTAGE 0
J 0
(-3100 1025);
PAINT SKYBLUE (-3100 1025);
DISPLAY INVISIBLE (-3100 1025);
FORCEADD FET_N_DUAL..5
(-3100 1300);
FORCEPROP 1 LASTPIN (-3100 1500) $PN 6
J 2
(-3047 1465);
DISPLAY 0.617021 (-3047 1465);
PAINT MONO (-3047 1465);
FORCEPROP 1 LASTPIN (-3300 1200) $PN 2
J 2
(-3297 1215);
DISPLAY 0.617021 (-3297 1215);
PAINT MONO (-3297 1215);
FORCEPROP 1 LASTPIN (-3100 1100) $PN 1
J 2
(-3042 1100);
DISPLAY 0.617021 (-3042 1100);
PAINT MONO (-3042 1100);
FORCEPROP 1 LAST MATERIAL FET
J 0
(-2900 1375);
DISPLAY 0.617021 (-2900 1375);
PAINT SKYBLUE (-2900 1375);
FORCEPROP 1 LAST VALUE NTJD4001N
J 0
(-2900 1425);
DISPLAY 0.617021 (-2900 1425);
PAINT SKYBLUE (-2900 1425);
FORCEPROP 1 LAST PART_NUMBER E40049-001
J 0
(-2900 1325);
DISPLAY 0.617021 (-2900 1325);
PAINT BLUE (-2900 1325);
FORCEPROP 1 LAST LOCATION Q4B2
J 0
(-2900 1475);
DISPLAY 0.617021 (-2900 1475);
PAINT AQUA (-2900 1475);
FORCEPROP 2 LAST ROOM PROC_SIDEBAND
J 1
(-2900 1575);
PAINT ORANGE (-2900 1575);
DISPLAY INVISIBLE (-2900 1575);
FORCEPROP 1 LAST PATH I32
J 0
(-2900 1350);
DISPLAY 0.978723 (-2900 1350);
PAINT BLUE (-2900 1350);
DISPLAY INVISIBLE (-2900 1350);
FORCEPROP 2 LAST CDS_LOCATION Q4B2
J 0
(-2900 1475);
DISPLAY 0.617021 (-2900 1475);
PAINT AQUA (-2900 1475);
DISPLAY INVISIBLE (-2900 1475);
FORCEPROP 2 LAST SEC 1
J 1
(-2900 1400);
PAINT MONO (-2900 1400);
DISPLAY INVISIBLE (-2900 1400);
FORCEPROP 2 LAST BOM_COST PROC_SIDEBAND
J 0
(-3100 1300);
PAINT MONO (-3100 1300);
DISPLAY INVISIBLE (-3100 1300);
FORCEPROP 2 LAST CDS_LIB mstr_discrete
J 1
(-3100 1300);
PAINT ORANGE (-3100 1300);
DISPLAY INVISIBLE (-3100 1300);
FORCEPROP 2 LAST SEC_TYPE SMLF
J 1
(-2900 1400);
PAINT MONO (-2900 1400);
DISPLAY INVISIBLE (-2900 1400);
FORCEPROP 1 LAST PACK_TYPE SMLF
J 0
(-2900 1150);
PAINT SKYBLUE (-2900 1150);
DISPLAY INVISIBLE (-2900 1150);
FORCEADD FET_N_DUAL..5
(-3100 700);
FORCEPROP 1 LASTPIN (-3100 900) $PN 3
J 2
(-3047 865);
DISPLAY 0.617021 (-3047 865);
PAINT MONO (-3047 865);
FORCEPROP 1 LASTPIN (-3300 600) $PN 5
J 2
(-3297 615);
DISPLAY 0.617021 (-3297 615);
PAINT MONO (-3297 615);
FORCEPROP 1 LASTPIN (-3100 500) $PN 4
J 2
(-3042 500);
DISPLAY 0.617021 (-3042 500);
PAINT MONO (-3042 500);
FORCEPROP 1 LAST MATERIAL FET
J 0
(-2900 775);
DISPLAY 0.617021 (-2900 775);
PAINT SKYBLUE (-2900 775);
FORCEPROP 1 LAST VALUE NTJD4001N
J 0
(-2900 825);
DISPLAY 0.617021 (-2900 825);
PAINT SKYBLUE (-2900 825);
FORCEPROP 1 LAST PART_NUMBER E40049-001
J 0
(-2900 725);
DISPLAY 0.617021 (-2900 725);
PAINT BLUE (-2900 725);
FORCEPROP 1 LAST LOCATION Q4B2
J 0
(-2900 875);
DISPLAY 0.617021 (-2900 875);
PAINT AQUA (-2900 875);
FORCEPROP 2 LAST ROOM PROC_SIDEBAND
J 1
(-2900 975);
PAINT ORANGE (-2900 975);
DISPLAY INVISIBLE (-2900 975);
FORCEPROP 1 LAST PATH I33
J 0
(-2900 750);
DISPLAY 0.978723 (-2900 750);
PAINT BLUE (-2900 750);
DISPLAY INVISIBLE (-2900 750);
FORCEPROP 2 LAST CDS_LOCATION Q4B2
J 0
(-2900 875);
DISPLAY 0.617021 (-2900 875);
PAINT AQUA (-2900 875);
DISPLAY INVISIBLE (-2900 875);
FORCEPROP 2 LAST SEC 2
J 1
(-2900 800);
PAINT MONO (-2900 800);
DISPLAY INVISIBLE (-2900 800);
FORCEPROP 2 LAST BOM_COST PROC_SIDEBAND
J 0
(-3100 700);
PAINT MONO (-3100 700);
DISPLAY INVISIBLE (-3100 700);
FORCEPROP 2 LAST CDS_LIB mstr_discrete
J 1
(-3100 700);
PAINT ORANGE (-3100 700);
DISPLAY INVISIBLE (-3100 700);
FORCEPROP 2 LAST SEC_TYPE SMLF
J 1
(-2900 800);
PAINT MONO (-2900 800);
DISPLAY INVISIBLE (-2900 800);
FORCEPROP 1 LAST PACK_TYPE SMLF
J 0
(-2900 550);
PAINT SKYBLUE (-2900 550);
DISPLAY INVISIBLE (-2900 550);
FORCEADD FET_N_DUAL..5
(-3100 3275);
FORCEPROP 1 LAST VALUE NTJD4001N
J 0
(-2900 3375);
DISPLAY 0.617021 (-2900 3375);
PAINT SKYBLUE (-2900 3375);
FORCEPROP 1 LASTPIN (-3100 3475) $PN 3
J 2
(-3047 3440);
DISPLAY 0.617021 (-3047 3440);
PAINT WHITE (-3047 3440);
FORCEPROP 1 LASTPIN (-3300 3175) $PN 5
J 2
(-3297 3190);
DISPLAY 0.617021 (-3297 3190);
PAINT WHITE (-3297 3190);
FORCEPROP 1 LASTPIN (-3100 3075) $PN 4
J 2
(-3042 3075);
DISPLAY 0.617021 (-3042 3075);
PAINT WHITE (-3042 3075);
FORCEPROP 1 LAST MATERIAL FET
J 0
(-2900 3325);
DISPLAY 0.617021 (-2900 3325);
PAINT SKYBLUE (-2900 3325);
FORCEPROP 1 LAST PART_NUMBER E40049-001
J 0
(-2900 3225);
DISPLAY 0.617021 (-2900 3225);
PAINT BLUE (-2900 3225);
FORCEPROP 1 LAST LOCATION Q7E3
J 0
(-2900 3275);
DISPLAY 0.617021 (-2900 3275);
PAINT AQUA (-2900 3275);
FORCEPROP 2 LAST ROOM PROC_SIDEBAND
J 1
(-2900 3525);
PAINT ORANGE (-2900 3525);
DISPLAY INVISIBLE (-2900 3525);
FORCEPROP 1 LAST PATH I51
J 0
(-2900 3325);
DISPLAY 0.978723 (-2900 3325);
PAINT BLUE (-2900 3325);
DISPLAY INVISIBLE (-2900 3325);
FORCEPROP 2 LAST CDS_LOCATION Q7E3
J 0
(-2900 3275);
DISPLAY 0.617021 (-2900 3275);
PAINT AQUA (-2900 3275);
DISPLAY INVISIBLE (-2900 3275);
FORCEPROP 2 LAST SEC 2
J 0
(-2900 3425);
DISPLAY 0.680851 (-2900 3425);
PAINT MONO (-2900 3425);
DISPLAY INVISIBLE (-2900 3425);
FORCEPROP 2 LAST BOM_COST PROC_SIDEBAND
J 0
(-3100 3275);
PAINT MONO (-3100 3275);
DISPLAY INVISIBLE (-3100 3275);
FORCEPROP 2 LAST CDS_LIB mstr_discrete
J 0
(-3100 3275);
PAINT ORANGE (-3100 3275);
DISPLAY INVISIBLE (-3100 3275);
FORCEPROP 2 LAST SEC_TYPE SMLF
J 0
(-2900 3425);
DISPLAY 1.021277 (-2900 3425);
PAINT ORANGE (-2900 3425);
DISPLAY INVISIBLE (-2900 3425);
FORCEPROP 1 LAST PACK_TYPE SMLF
J 0
(-2900 3125);
PAINT SKYBLUE (-2900 3125);
DISPLAY INVISIBLE (-2900 3125);
FORCEADD FET_N_DUAL..5
(-3100 3950);
FORCEPROP 1 LASTPIN (-3100 4150) $PN 6
J 2
(-3047 4115);
DISPLAY 0.617021 (-3047 4115);
PAINT WHITE (-3047 4115);
FORCEPROP 1 LASTPIN (-3300 3850) $PN 2
J 2
(-3297 3865);
DISPLAY 0.617021 (-3297 3865);
PAINT WHITE (-3297 3865);
FORCEPROP 1 LASTPIN (-3100 3750) $PN 1
J 2
(-3042 3750);
DISPLAY 0.617021 (-3042 3750);
PAINT WHITE (-3042 3750);
FORCEPROP 1 LAST MATERIAL FET
J 0
(-2900 4000);
DISPLAY 0.617021 (-2900 4000);
PAINT SKYBLUE (-2900 4000);
FORCEPROP 1 LAST VALUE NTJD4001N
J 0
(-2900 4050);
DISPLAY 0.617021 (-2900 4050);
PAINT SKYBLUE (-2900 4050);
FORCEPROP 1 LAST LOCATION Q7E3
J 0
(-2900 3950);
DISPLAY 0.617021 (-2900 3950);
PAINT AQUA (-2900 3950);
FORCEPROP 1 LAST PART_NUMBER E40049-001
J 0
(-2900 3900);
DISPLAY 0.617021 (-2900 3900);
PAINT BLUE (-2900 3900);
FORCEPROP 2 LAST ROOM PROC_SIDEBAND
J 1
(-2900 4200);
PAINT ORANGE (-2900 4200);
DISPLAY INVISIBLE (-2900 4200);
FORCEPROP 1 LAST PATH I52
J 0
(-2900 4000);
DISPLAY 0.978723 (-2900 4000);
PAINT BLUE (-2900 4000);
DISPLAY INVISIBLE (-2900 4000);
FORCEPROP 2 LAST CDS_LOCATION Q7E3
J 0
(-2900 3950);
DISPLAY 0.617021 (-2900 3950);
PAINT AQUA (-2900 3950);
DISPLAY INVISIBLE (-2900 3950);
FORCEPROP 2 LAST SEC 1
J 0
(-2900 4100);
DISPLAY 0.680851 (-2900 4100);
PAINT MONO (-2900 4100);
DISPLAY INVISIBLE (-2900 4100);
FORCEPROP 2 LAST BOM_COST PROC_SIDEBAND
J 0
(-3100 3950);
PAINT MONO (-3100 3950);
DISPLAY INVISIBLE (-3100 3950);
FORCEPROP 2 LAST CDS_LIB mstr_discrete
J 0
(-3100 3950);
PAINT ORANGE (-3100 3950);
DISPLAY INVISIBLE (-3100 3950);
FORCEPROP 2 LAST SEC_TYPE SMLF
J 0
(-2900 4100);
DISPLAY 1.021277 (-2900 4100);
PAINT ORANGE (-2900 4100);
DISPLAY INVISIBLE (-2900 4100);
FORCEPROP 1 LAST PACK_TYPE SMLF
J 0
(-2900 3800);
PAINT SKYBLUE (-2900 3800);
DISPLAY INVISIBLE (-2900 3800);
FORCEADD OFFPAGE..5
R 2
(3655 5025);
FORCEPROP 2 LAST $XR2 93 
J 0
(4024 5025);
DISPLAY 0.638298 (4024 5025);
PAINT MONO (4024 5025);
FORCEPROP 2 LAST $XR1 95 
J 0
(3934 5025);
DISPLAY 0.638298 (3934 5025);
PAINT MONO (3934 5025);
FORCEPROP 2 LAST $XR0 21 
J 0
(3844 5025);
DISPLAY 0.638298 (3844 5025);
PAINT MONO (3844 5025);
FORCEPROP 2 LAST PATH I58
J 0
(4000 5075);
DISPLAY 1.021277 (4000 5075);
PAINT ORANGE (4000 5075);
DISPLAY INVISIBLE (4000 5075);
FORCEPROP 1 LAST COMMENT_BODY TRUE
J 2
(3555 4950);
DISPLAY 0.978723 (3555 4950);
PAINT GREEN (3555 4950);
DISPLAY INVISIBLE (3555 4950);
FORCEPROP 1 LAST OFFPAGE TRUE
J 2
(3330 4900);
DISPLAY 0.978723 (3330 4900);
PAINT GREEN (3330 4900);
DISPLAY INVISIBLE (3330 4900);
FORCEPROP 2 LAST CDS_LIB mstr_standard
J 0
(3655 5025);
DISPLAY 1.340426 (3655 5025);
PAINT ORANGE (3655 5025);
DISPLAY INVISIBLE (3655 5025);
FORCEADD FET_N_DUAL..5
(3050 4725);
FORCEPROP 1 LASTPIN (3050 4925) $PN 3
J 2
(3103 4890);
DISPLAY 0.617021 (3103 4890);
PAINT WHITE (3103 4890);
FORCEPROP 1 LASTPIN (2850 4625) $PN 5
J 2
(2853 4640);
DISPLAY 0.617021 (2853 4640);
PAINT WHITE (2853 4640);
FORCEPROP 1 LASTPIN (3050 4525) $PN 4
J 2
(3108 4525);
DISPLAY 0.617021 (3108 4525);
PAINT WHITE (3108 4525);
FORCEPROP 1 LAST MATERIAL FET
J 0
(3250 4625);
DISPLAY 0.617021 (3250 4625);
PAINT SKYBLUE (3250 4625);
FORCEPROP 1 LAST VALUE NTJD4001N
J 0
(3250 4675);
DISPLAY 0.617021 (3250 4675);
PAINT SKYBLUE (3250 4675);
FORCEPROP 1 LAST PART_NUMBER E40049-001
J 0
(3250 4525);
DISPLAY 0.617021 (3250 4525);
PAINT BLUE (3250 4525);
FORCEPROP 1 LAST LOCATION Q7E5
J 0
(3250 4725);
DISPLAY 0.617021 (3250 4725);
PAINT AQUA (3250 4725);
FORCEPROP 2 LAST ROOM HOT_EVENTS
J 0
(3250 4825);
PAINT ORANGE (3250 4825);
DISPLAY INVISIBLE (3250 4825);
FORCEPROP 1 LAST PATH I59
J 0
(3250 4775);
DISPLAY 0.978723 (3250 4775);
PAINT BLUE (3250 4775);
DISPLAY INVISIBLE (3250 4775);
FORCEPROP 2 LAST CDS_LOCATION Q7E5
J 0
(3250 4725);
DISPLAY 0.617021 (3250 4725);
PAINT AQUA (3250 4725);
DISPLAY INVISIBLE (3250 4725);
FORCEPROP 2 LAST SEC 2
J 0
(3250 4825);
DISPLAY 0.680851 (3250 4825);
PAINT MONO (3250 4825);
DISPLAY INVISIBLE (3250 4825);
FORCEPROP 2 LAST BOM_COST PROC_SIDEBAND
J 0
(3050 4725);
PAINT MONO (3050 4725);
DISPLAY INVISIBLE (3050 4725);
FORCEPROP 2 LAST CDS_LIB mstr_discrete
J 0
(3050 4725);
PAINT ORANGE (3050 4725);
DISPLAY INVISIBLE (3050 4725);
FORCEPROP 2 LAST SEC_TYPE SMLF
J 0
(3250 4825);
DISPLAY 1.021277 (3250 4825);
PAINT ORANGE (3250 4825);
DISPLAY INVISIBLE (3250 4825);
FORCEPROP 1 LAST PACK_TYPE SMLF
J 0
(3250 4575);
DISPLAY 0.978723 (3250 4575);
PAINT SKYBLUE (3250 4575);
DISPLAY INVISIBLE (3250 4575);
FORCEADD OFFPAGE..2
(-700 4200);
FORCEPROP 2 LAST $XR2 93 
J 0
(-331 4200);
DISPLAY 0.638298 (-331 4200);
PAINT MONO (-331 4200);
FORCEPROP 2 LAST $XR1 95 
J 0
(-421 4200);
DISPLAY 0.638298 (-421 4200);
PAINT MONO (-421 4200);
FORCEPROP 2 LAST $XR0 21 
J 0
(-511 4200);
DISPLAY 0.638298 (-511 4200);
PAINT MONO (-511 4200);
FORCEPROP 2 LAST PATH I6
J 0
(-325 4250);
DISPLAY 1.021277 (-325 4250);
PAINT ORANGE (-325 4250);
DISPLAY INVISIBLE (-325 4250);
FORCEPROP 1 LAST COMMENT_BODY TRUE
J 0
(-745 4105);
DISPLAY 1.170213 (-745 4105);
PAINT GREEN (-745 4105);
DISPLAY INVISIBLE (-745 4105);
FORCEPROP 1 LAST OFFPAGE TRUE
J 0
(-375 4075);
PAINT GREEN (-375 4075);
DISPLAY INVISIBLE (-375 4075);
FORCEPROP 2 LAST CDS_LIB mstr_standard
J 0
(-700 4200);
DISPLAY 1.361702 (-700 4200);
PAINT ORANGE (-700 4200);
DISPLAY INVISIBLE (-700 4200);
FORCEPROP 2 LAST ROOM SMART_CLST
J 0
(-950 4275);
DISPLAY 1.361702 (-950 4275);
PAINT ORANGE (-950 4275);
DISPLAY INVISIBLE (-950 4275);
FORCEADD GND..1
(3050 4225);
FORCEPROP 3 LASTPIN (3050 4275) SIG_NAME GND\g
J 0
(3060 4285);
DISPLAY 0.659574 (3060 4285);
PAINT MONO (3060 4285);
DISPLAY INVISIBLE (3060 4285);
FORCEPROP 1 LAST HDL_POWER GND
J 0
(3050 4375);
DISPLAY 1.170213 (3050 4375);
PAINT GREEN (3050 4375);
DISPLAY INVISIBLE (3050 4375);
FORCEPROP 2 LAST ROOM PROCHOT_MEMHOT_ISO
J 0
(2675 4300);
PAINT ORANGE (2675 4300);
DISPLAY INVISIBLE (2675 4300);
FORCEPROP 1 LAST PATH I60
J 0
(3125 4225);
DISPLAY 0.872340 (3125 4225);
PAINT AQUA (3125 4225);
DISPLAY INVISIBLE (3125 4225);
FORCEPROP 1 LAST BODY_TYPE PLUMBING
J 0
(3005 4182);
DISPLAY 0.340426 (3005 4182);
PAINT GREEN (3005 4182);
DISPLAY INVISIBLE (3005 4182);
FORCEPROP 2 LAST CDS_LIB mstr_symbols
J 0
(3050 4225);
PAINT ORANGE (3050 4225);
DISPLAY INVISIBLE (3050 4225);
FORCEPROP 1 LAST SIZE 1B
J 0
(3125 4175);
DISPLAY 1.170213 (3125 4175);
PAINT GREEN (3125 4175);
DISPLAY INVISIBLE (3125 4175);
FORCEPROP 1 LAST VOLTAGE 0.0V
J 0
(3005 4182);
DISPLAY 0.340426 (3005 4182);
PAINT SKYBLUE (3005 4182);
DISPLAY INVISIBLE (3005 4182);
FORCEADD P3V3..1
(2475 5050);
FORCEPROP 3 LASTPIN (2475 5000) SIG_NAME P3V3\g
J 0
(2485 5010);
DISPLAY 0.659574 (2485 5010);
PAINT MONO (2485 5010);
DISPLAY INVISIBLE (2485 5010);
FORCEPROP 1 LAST HDL_POWER P3V3
J 0
(2150 4925);
DISPLAY 1.170213 (2150 4925);
PAINT GREEN (2150 4925);
DISPLAY INVISIBLE (2150 4925);
FORCEPROP 2 LAST ROOM PROCHOT_MEMHOT_ISO
J 0
(2275 5150);
DISPLAY 1.340426 (2275 5150);
PAINT ORANGE (2275 5150);
DISPLAY INVISIBLE (2275 5150);
FORCEPROP 1 LAST PATH I61
J 0
(2520 5052);
DISPLAY 0.340426 (2520 5052);
PAINT GREEN (2520 5052);
DISPLAY INVISIBLE (2520 5052);
FORCEPROP 1 LAST BODY_TYPE PLUMBING
J 0
(2430 5007);
DISPLAY 0.446809 (2430 5007);
PAINT GREEN (2430 5007);
DISPLAY INVISIBLE (2430 5007);
FORCEPROP 1 LAST SIZE 1B
J 0
(2520 5072);
DISPLAY 0.446809 (2520 5072);
PAINT GREEN (2520 5072);
DISPLAY INVISIBLE (2520 5072);
FORCEPROP 2 LAST CDS_LIB mstr_symbols
J 0
(2475 5050);
PAINT ORANGE (2475 5050);
DISPLAY INVISIBLE (2475 5050);
FORCEPROP 1 LAST VOLTAGE 3.3V
J 0
(2430 5007);
DISPLAY 0.340426 (2430 5007);
PAINT SKYBLUE (2430 5007);
DISPLAY INVISIBLE (2430 5007);
FORCEADD RES..2
R 2
(2475 4800);
FORCEPROP 1 LAST PART_NUMBER G21796-072
R 1
J 2
(2535 5000);
DISPLAY 0.617021 (2535 5000);
PAINT BLUE (2535 5000);
FORCEPROP 1 LASTPIN (2475 4900) $PN 1
J 2
(2470 4862);
DISPLAY 0.617021 (2470 4862);
PAINT WHITE (2470 4862);
FORCEPROP 1 LASTPIN (2475 4700) $PN 2
J 2
(2470 4710);
DISPLAY 0.617021 (2470 4710);
PAINT WHITE (2470 4710);
FORCEPROP 1 LAST TOLERANCE 1%
J 2
(2430 4800);
DISPLAY 0.617021 (2430 4800);
PAINT SKYBLUE (2430 4800);
FORCEPROP 1 LAST VALUE 4.75K
J 2
(2430 4850);
DISPLAY 0.617021 (2430 4850);
PAINT SKYBLUE (2430 4850);
FORCEPROP 1 LAST LOCATION R7E10
J 2
(2430 4900);
DISPLAY 0.617021 (2430 4900);
PAINT AQUA (2430 4900);
FORCEPROP 1 LAST WATTAGE 1/16W
J 2
(2435 4750);
DISPLAY 0.617021 (2435 4750);
PAINT SKYBLUE (2435 4750);
FORCEPROP 1 LAST MATERIAL CHIP
J 2
(2435 4700);
DISPLAY 0.638298 (2435 4700);
PAINT SKYBLUE (2435 4700);
FORCEPROP 1 LAST PACK_TYPE 0402
J 2
(2435 4650);
DISPLAY 0.617021 (2435 4650);
PAINT SKYBLUE (2435 4650);
FORCEPROP 2 LAST ROOM HOT_EVENTS
J 2
(2425 4975);
PAINT PEACH (2425 4975);
DISPLAY INVISIBLE (2425 4975);
FORCEPROP 1 LAST PATH I62
J 2
(2425 4975);
DISPLAY 0.978723 (2425 4975);
PAINT WHITE (2425 4975);
DISPLAY INVISIBLE (2425 4975);
FORCEPROP 2 LAST CDS_LOCATION R7E10
J 2
(2430 4900);
DISPLAY 0.617021 (2430 4900);
PAINT AQUA (2430 4900);
DISPLAY INVISIBLE (2430 4900);
FORCEPROP 2 LAST $SEC 1
J 1
(2425 5025);
PAINT MONO (2425 5025);
DISPLAY INVISIBLE (2425 5025);
FORCEPROP 2 LAST CDS_SEC 1
J 1
(2425 5025);
PAINT MONO (2425 5025);
DISPLAY INVISIBLE (2425 5025);
FORCEPROP 2 LAST BOM_COST PROC_SIDEBAND
J 2
(2475 4800);
PAINT MONO (2475 4800);
DISPLAY INVISIBLE (2475 4800);
FORCEPROP 2 LAST CDS_LIB mstr_discrete
J 2
(2475 4800);
DISPLAY 1.340426 (2475 4800);
PAINT ORANGE (2475 4800);
DISPLAY INVISIBLE (2475 4800);
FORCEADD GND..1
(2475 4025);
FORCEPROP 3 LASTPIN (2475 4075) SIG_NAME GND\g
J 0
(2485 4085);
DISPLAY 0.659574 (2485 4085);
PAINT MONO (2485 4085);
DISPLAY INVISIBLE (2485 4085);
FORCEPROP 1 LAST HDL_POWER GND
J 0
(2475 4175);
DISPLAY 1.170213 (2475 4175);
PAINT GREEN (2475 4175);
DISPLAY INVISIBLE (2475 4175);
FORCEPROP 2 LAST ROOM PROCHOT_MEMHOT_ISO
J 0
(2100 4100);
PAINT ORANGE (2100 4100);
DISPLAY INVISIBLE (2100 4100);
FORCEPROP 1 LAST PATH I63
J 0
(2550 4025);
DISPLAY 0.872340 (2550 4025);
PAINT AQUA (2550 4025);
DISPLAY INVISIBLE (2550 4025);
FORCEPROP 1 LAST BODY_TYPE PLUMBING
J 0
(2430 3982);
DISPLAY 0.340426 (2430 3982);
PAINT GREEN (2430 3982);
DISPLAY INVISIBLE (2430 3982);
FORCEPROP 2 LAST CDS_LIB mstr_symbols
J 0
(2475 4025);
PAINT ORANGE (2475 4025);
DISPLAY INVISIBLE (2475 4025);
FORCEPROP 1 LAST SIZE 1B
J 0
(2550 3975);
DISPLAY 1.170213 (2550 3975);
PAINT GREEN (2550 3975);
DISPLAY INVISIBLE (2550 3975);
FORCEPROP 1 LAST VOLTAGE 0.0V
J 0
(2430 3982);
DISPLAY 0.340426 (2430 3982);
PAINT SKYBLUE (2430 3982);
DISPLAY INVISIBLE (2430 3982);
FORCEADD OFFPAGE..1
(500 4175);
FORCEPROP 2 LAST $XR1 145 
J 0
(128 4175);
DISPLAY 0.638298 (128 4175);
PAINT MONO (128 4175);
FORCEPROP 2 LAST $XR0 201 
J 0
(248 4175);
DISPLAY 0.638298 (248 4175);
PAINT MONO (248 4175);
FORCEPROP 2 LAST PATH I66
J 0
(200 4225);
DISPLAY 1.021277 (200 4225);
PAINT ORANGE (200 4225);
DISPLAY INVISIBLE (200 4225);
FORCEPROP 1 LAST COMMENT_BODY TRUE
J 0
(625 4075);
DISPLAY 0.978723 (625 4075);
PAINT PEACH (625 4075);
DISPLAY INVISIBLE (625 4075);
FORCEPROP 1 LAST OFFPAGE TRUE
J 0
(825 4050);
DISPLAY 0.978723 (825 4050);
PAINT GREEN (825 4050);
DISPLAY INVISIBLE (825 4050);
FORCEPROP 2 LAST CDS_LIB mstr_standard
J 0
(500 4175);
DISPLAY 1.340426 (500 4175);
PAINT ORANGE (500 4175);
DISPLAY INVISIBLE (500 4175);
FORCEPROP 2 LAST ROOM PROCHOT_MEMHOT_ISO
J 0
(250 4225);
DISPLAY 0.978723 (250 4225);
PAINT ORANGE (250 4225);
DISPLAY INVISIBLE (250 4225);
FORCEADD OFFPAGE..1
(500 4275);
FORCEPROP 2 LAST $XR0 201 
J 0
(248 4275);
DISPLAY 0.638298 (248 4275);
PAINT MONO (248 4275);
FORCEPROP 2 LAST PATH I67
J 0
(200 4325);
DISPLAY 1.021277 (200 4325);
PAINT ORANGE (200 4325);
DISPLAY INVISIBLE (200 4325);
FORCEPROP 1 LAST COMMENT_BODY TRUE
J 0
(625 4175);
DISPLAY 0.978723 (625 4175);
PAINT PEACH (625 4175);
DISPLAY INVISIBLE (625 4175);
FORCEPROP 1 LAST OFFPAGE TRUE
J 0
(825 4150);
DISPLAY 0.978723 (825 4150);
PAINT GREEN (825 4150);
DISPLAY INVISIBLE (825 4150);
FORCEPROP 2 LAST ROOM PROCHOT_MEMHOT_ISO
J 0
(250 4325);
DISPLAY 0.978723 (250 4325);
PAINT ORANGE (250 4325);
DISPLAY INVISIBLE (250 4325);
FORCEPROP 2 LAST CDS_LIB mstr_standard
J 0
(500 4275);
DISPLAY 1.340426 (500 4275);
PAINT ORANGE (500 4275);
DISPLAY INVISIBLE (500 4275);
FORCEADD OFFPAGE..5
R 2
(3755 3575);
FORCEPROP 2 LAST $XR2 93 
J 0
(4124 3575);
DISPLAY 0.638298 (4124 3575);
PAINT MONO (4124 3575);
FORCEPROP 2 LAST $XR1 95 
J 0
(4034 3575);
DISPLAY 0.638298 (4034 3575);
PAINT MONO (4034 3575);
FORCEPROP 2 LAST $XR0 55 
J 0
(3944 3575);
DISPLAY 0.638298 (3944 3575);
PAINT MONO (3944 3575);
FORCEPROP 2 LAST CDS_LIB mstr_standard
J 0
(3755 3575);
DISPLAY 1.340426 (3755 3575);
PAINT ORANGE (3755 3575);
DISPLAY INVISIBLE (3755 3575);
FORCEPROP 1 LAST OFFPAGE TRUE
J 2
(3430 3450);
DISPLAY 0.978723 (3430 3450);
PAINT GREEN (3430 3450);
DISPLAY INVISIBLE (3430 3450);
FORCEPROP 1 LAST COMMENT_BODY TRUE
J 2
(3655 3500);
DISPLAY 0.978723 (3655 3500);
PAINT GREEN (3655 3500);
DISPLAY INVISIBLE (3655 3500);
FORCEPROP 2 LAST PATH I68
J 0
(4100 3625);
DISPLAY 1.021277 (4100 3625);
PAINT ORANGE (4100 3625);
DISPLAY INVISIBLE (4100 3625);
FORCEADD FET_N_DUAL..5
(3225 3250);
FORCEPROP 1 LASTPIN (3225 3050) $PN 4
J 2
(3283 3050);
DISPLAY 0.617021 (3283 3050);
PAINT WHITE (3283 3050);
FORCEPROP 1 LASTPIN (3025 3150) $PN 5
J 2
(3028 3165);
DISPLAY 0.617021 (3028 3165);
PAINT WHITE (3028 3165);
FORCEPROP 1 LASTPIN (3225 3450) $PN 3
J 2
(3278 3415);
DISPLAY 0.617021 (3278 3415);
PAINT WHITE (3278 3415);
FORCEPROP 1 LAST VALUE NTJD4001N
J 0
(3425 3200);
DISPLAY 0.617021 (3425 3200);
PAINT SKYBLUE (3425 3200);
FORCEPROP 1 LAST MATERIAL FET
J 0
(3425 3150);
DISPLAY 0.617021 (3425 3150);
PAINT SKYBLUE (3425 3150);
FORCEPROP 1 LAST LOCATION Q7E6
J 0
(3425 3250);
DISPLAY 0.617021 (3425 3250);
PAINT AQUA (3425 3250);
FORCEPROP 1 LAST PART_NUMBER E40049-001
J 0
(3425 3050);
DISPLAY 0.617021 (3425 3050);
PAINT BLUE (3425 3050);
FORCEPROP 1 LAST PACK_TYPE SMLF
J 0
(3425 3100);
DISPLAY 0.978723 (3425 3100);
PAINT SKYBLUE (3425 3100);
DISPLAY INVISIBLE (3425 3100);
FORCEPROP 2 LAST SEC_TYPE SMLF
J 0
(3425 3350);
DISPLAY 1.021277 (3425 3350);
PAINT ORANGE (3425 3350);
DISPLAY INVISIBLE (3425 3350);
FORCEPROP 2 LAST CDS_LIB mstr_discrete
J 0
(3225 3250);
PAINT ORANGE (3225 3250);
DISPLAY INVISIBLE (3225 3250);
FORCEPROP 2 LAST BOM_COST PROC_SIDEBAND
J 0
(3225 3250);
PAINT MONO (3225 3250);
DISPLAY INVISIBLE (3225 3250);
FORCEPROP 2 LAST SEC 2
J 0
(3425 3350);
DISPLAY 0.680851 (3425 3350);
PAINT MONO (3425 3350);
DISPLAY INVISIBLE (3425 3350);
FORCEPROP 2 LAST CDS_LOCATION Q7E6
J 0
(3425 3250);
DISPLAY 0.617021 (3425 3250);
PAINT AQUA (3425 3250);
DISPLAY INVISIBLE (3425 3250);
FORCEPROP 1 LAST PATH I69
J 0
(3425 3300);
DISPLAY 0.978723 (3425 3300);
PAINT BLUE (3425 3300);
DISPLAY INVISIBLE (3425 3300);
FORCEPROP 2 LAST ROOM HOT_EVENTS
J 0
(3425 3350);
PAINT ORANGE (3425 3350);
DISPLAY INVISIBLE (3425 3350);
FORCEADD GND..1
(3225 2825);
FORCEPROP 3 LASTPIN (3225 2875) SIG_NAME GND\g
J 0
(3235 2885);
DISPLAY 0.659574 (3235 2885);
PAINT MONO (3235 2885);
DISPLAY INVISIBLE (3235 2885);
FORCEPROP 1 LAST VOLTAGE 0.0V
J 0
(3180 2782);
DISPLAY 0.340426 (3180 2782);
PAINT SKYBLUE (3180 2782);
DISPLAY INVISIBLE (3180 2782);
FORCEPROP 2 LAST CDS_LIB mstr_symbols
J 0
(3225 2825);
PAINT ORANGE (3225 2825);
DISPLAY INVISIBLE (3225 2825);
FORCEPROP 1 LAST SIZE 1B
J 0
(3300 2775);
DISPLAY 1.170213 (3300 2775);
PAINT GREEN (3300 2775);
DISPLAY INVISIBLE (3300 2775);
FORCEPROP 1 LAST BODY_TYPE PLUMBING
J 0
(3180 2782);
DISPLAY 0.340426 (3180 2782);
PAINT GREEN (3180 2782);
DISPLAY INVISIBLE (3180 2782);
FORCEPROP 1 LAST PATH I70
J 0
(3300 2825);
DISPLAY 0.872340 (3300 2825);
PAINT AQUA (3300 2825);
DISPLAY INVISIBLE (3300 2825);
FORCEPROP 2 LAST ROOM PROCHOT_MEMHOT_ISO
J 0
(2850 2900);
PAINT ORANGE (2850 2900);
DISPLAY INVISIBLE (2850 2900);
FORCEPROP 1 LAST HDL_POWER GND
J 0
(3225 2975);
DISPLAY 1.170213 (3225 2975);
PAINT GREEN (3225 2975);
DISPLAY INVISIBLE (3225 2975);
FORCEADD P3V3..1
(2550 3600);
FORCEPROP 3 LASTPIN (2550 3550) SIG_NAME P3V3\g
J 0
(2560 3560);
DISPLAY 0.659574 (2560 3560);
PAINT MONO (2560 3560);
DISPLAY INVISIBLE (2560 3560);
FORCEPROP 1 LAST HDL_POWER P3V3
J 0
(2225 3475);
DISPLAY 1.170213 (2225 3475);
PAINT GREEN (2225 3475);
DISPLAY INVISIBLE (2225 3475);
FORCEPROP 2 LAST ROOM PROCHOT_MEMHOT_ISO
J 0
(2350 3700);
DISPLAY 1.340426 (2350 3700);
PAINT ORANGE (2350 3700);
DISPLAY INVISIBLE (2350 3700);
FORCEPROP 1 LAST PATH I71
J 0
(2595 3602);
DISPLAY 0.340426 (2595 3602);
PAINT GREEN (2595 3602);
DISPLAY INVISIBLE (2595 3602);
FORCEPROP 1 LAST BODY_TYPE PLUMBING
J 0
(2505 3557);
DISPLAY 0.446809 (2505 3557);
PAINT GREEN (2505 3557);
DISPLAY INVISIBLE (2505 3557);
FORCEPROP 1 LAST SIZE 1B
J 0
(2595 3622);
DISPLAY 0.446809 (2595 3622);
PAINT GREEN (2595 3622);
DISPLAY INVISIBLE (2595 3622);
FORCEPROP 2 LAST CDS_LIB mstr_symbols
J 0
(2550 3600);
PAINT ORANGE (2550 3600);
DISPLAY INVISIBLE (2550 3600);
FORCEPROP 1 LAST VOLTAGE 3.3V
J 0
(2505 3557);
DISPLAY 0.340426 (2505 3557);
PAINT SKYBLUE (2505 3557);
DISPLAY INVISIBLE (2505 3557);
FORCEADD RES..2
R 2
(2550 3375);
FORCEPROP 1 LASTPIN (2550 3475) $PN 1
J 2
(2545 3437);
DISPLAY 0.617021 (2545 3437);
PAINT WHITE (2545 3437);
FORCEPROP 1 LASTPIN (2550 3275) $PN 2
J 2
(2545 3285);
DISPLAY 0.617021 (2545 3285);
PAINT WHITE (2545 3285);
FORCEPROP 1 LAST TOLERANCE 1%
J 2
(2505 3375);
DISPLAY 0.617021 (2505 3375);
PAINT SKYBLUE (2505 3375);
FORCEPROP 1 LAST VALUE 4.75K
J 2
(2505 3425);
DISPLAY 0.617021 (2505 3425);
PAINT SKYBLUE (2505 3425);
FORCEPROP 1 LAST LOCATION R7E11
J 2
(2505 3475);
DISPLAY 0.617021 (2505 3475);
PAINT AQUA (2505 3475);
FORCEPROP 1 LAST PACK_TYPE 0402
J 2
(2510 3275);
DISPLAY 0.617021 (2510 3275);
PAINT SKYBLUE (2510 3275);
FORCEPROP 1 LAST WATTAGE 1/16W
J 2
(2510 3325);
DISPLAY 0.617021 (2510 3325);
PAINT SKYBLUE (2510 3325);
FORCEPROP 1 LAST PART_NUMBER G21796-072
R 1
J 0
(2610 3250);
DISPLAY 0.617021 (2610 3250);
PAINT BLUE (2610 3250);
FORCEPROP 1 LAST MATERIAL CHIP
J 2
(2510 3225);
DISPLAY 0.638298 (2510 3225);
PAINT SKYBLUE (2510 3225);
FORCEPROP 2 LAST ROOM HOT_EVENTS
J 2
(2500 3550);
PAINT PEACH (2500 3550);
DISPLAY INVISIBLE (2500 3550);
FORCEPROP 1 LAST PATH I72
J 2
(2500 3550);
DISPLAY 0.978723 (2500 3550);
PAINT WHITE (2500 3550);
DISPLAY INVISIBLE (2500 3550);
FORCEPROP 2 LAST CDS_LOCATION R7E11
J 2
(2505 3475);
DISPLAY 0.617021 (2505 3475);
PAINT AQUA (2505 3475);
DISPLAY INVISIBLE (2505 3475);
FORCEPROP 2 LAST $SEC 1
J 1
(2500 3600);
PAINT MONO (2500 3600);
DISPLAY INVISIBLE (2500 3600);
FORCEPROP 2 LAST CDS_SEC 1
J 1
(2500 3600);
PAINT MONO (2500 3600);
DISPLAY INVISIBLE (2500 3600);
FORCEPROP 2 LAST BOM_COST PROC_SIDEBAND
J 2
(2550 3375);
PAINT MONO (2550 3375);
DISPLAY INVISIBLE (2550 3375);
FORCEPROP 2 LAST CDS_LIB mstr_discrete
J 2
(2550 3375);
DISPLAY 1.340426 (2550 3375);
PAINT ORANGE (2550 3375);
DISPLAY INVISIBLE (2550 3375);
FORCEADD GND..1
(2550 2575);
FORCEPROP 3 LASTPIN (2550 2625) SIG_NAME GND\g
J 0
(2560 2635);
DISPLAY 0.659574 (2560 2635);
PAINT MONO (2560 2635);
DISPLAY INVISIBLE (2560 2635);
FORCEPROP 1 LAST HDL_POWER GND
J 0
(2550 2725);
DISPLAY 1.170213 (2550 2725);
PAINT GREEN (2550 2725);
DISPLAY INVISIBLE (2550 2725);
FORCEPROP 2 LAST ROOM PROCHOT_MEMHOT_ISO
J 0
(2175 2650);
PAINT ORANGE (2175 2650);
DISPLAY INVISIBLE (2175 2650);
FORCEPROP 1 LAST PATH I73
J 0
(2625 2575);
DISPLAY 0.872340 (2625 2575);
PAINT AQUA (2625 2575);
DISPLAY INVISIBLE (2625 2575);
FORCEPROP 1 LAST BODY_TYPE PLUMBING
J 0
(2505 2532);
DISPLAY 0.340426 (2505 2532);
PAINT GREEN (2505 2532);
DISPLAY INVISIBLE (2505 2532);
FORCEPROP 1 LAST SIZE 1B
J 0
(2625 2525);
DISPLAY 1.170213 (2625 2525);
PAINT GREEN (2625 2525);
DISPLAY INVISIBLE (2625 2525);
FORCEPROP 2 LAST CDS_LIB mstr_symbols
J 0
(2550 2575);
PAINT ORANGE (2550 2575);
DISPLAY INVISIBLE (2550 2575);
FORCEPROP 1 LAST VOLTAGE 0.0V
J 0
(2505 2532);
DISPLAY 0.340426 (2505 2532);
PAINT SKYBLUE (2505 2532);
DISPLAY INVISIBLE (2505 2532);
FORCEADD OFFPAGE..1
(550 2725);
FORCEPROP 2 LAST $XR1 145 
J 0
(178 2725);
DISPLAY 0.638298 (178 2725);
PAINT MONO (178 2725);
FORCEPROP 2 LAST $XR0 206 
J 0
(298 2725);
DISPLAY 0.638298 (298 2725);
PAINT MONO (298 2725);
FORCEPROP 2 LAST PATH I76
J 0
(250 2775);
DISPLAY 1.021277 (250 2775);
PAINT ORANGE (250 2775);
DISPLAY INVISIBLE (250 2775);
FORCEPROP 1 LAST COMMENT_BODY TRUE
J 0
(675 2625);
DISPLAY 0.978723 (675 2625);
PAINT PEACH (675 2625);
DISPLAY INVISIBLE (675 2625);
FORCEPROP 1 LAST OFFPAGE TRUE
J 0
(875 2600);
DISPLAY 0.978723 (875 2600);
PAINT GREEN (875 2600);
DISPLAY INVISIBLE (875 2600);
FORCEPROP 2 LAST CDS_LIB mstr_standard
J 0
(550 2725);
DISPLAY 1.340426 (550 2725);
PAINT ORANGE (550 2725);
DISPLAY INVISIBLE (550 2725);
FORCEPROP 2 LAST ROOM PROCHOT_MEMHOT_ISO
J 0
(300 2775);
DISPLAY 0.978723 (300 2775);
PAINT ORANGE (300 2775);
DISPLAY INVISIBLE (300 2775);
FORCEADD OFFPAGE..1
(550 2825);
FORCEPROP 2 LAST $XR0 206 
J 0
(298 2825);
DISPLAY 0.638298 (298 2825);
PAINT MONO (298 2825);
FORCEPROP 2 LAST PATH I77
J 0
(250 2875);
DISPLAY 1.021277 (250 2875);
PAINT ORANGE (250 2875);
DISPLAY INVISIBLE (250 2875);
FORCEPROP 1 LAST COMMENT_BODY TRUE
J 0
(675 2725);
DISPLAY 0.978723 (675 2725);
PAINT PEACH (675 2725);
DISPLAY INVISIBLE (675 2725);
FORCEPROP 1 LAST OFFPAGE TRUE
J 0
(875 2700);
DISPLAY 0.978723 (875 2700);
PAINT GREEN (875 2700);
DISPLAY INVISIBLE (875 2700);
FORCEPROP 2 LAST ROOM PROCHOT_MEMHOT_ISO
J 0
(300 2875);
DISPLAY 0.978723 (300 2875);
PAINT ORANGE (300 2875);
DISPLAY INVISIBLE (300 2875);
FORCEPROP 2 LAST CDS_LIB mstr_standard
J 0
(550 2825);
DISPLAY 1.340426 (550 2825);
PAINT ORANGE (550 2825);
DISPLAY INVISIBLE (550 2825);
FORCEADD CAP_A..1
(700 4775);
FORCEPROP 1 LASTPIN (700 4675) $PN 2
J 0
(710 4655);
DISPLAY 0.617021 (710 4655);
PAINT ORANGE (710 4655);
FORCEPROP 1 LASTPIN (700 4875) $PN 1
J 0
(710 4855);
DISPLAY 0.617021 (710 4855);
PAINT ORANGE (710 4855);
FORCEPROP 1 LAST MATERIAL X7R
J 0
(750 4675);
DISPLAY 0.617021 (750 4675);
PAINT SKYBLUE (750 4675);
FORCEPROP 1 LAST PACK_TYPE 0402V
J 0
(750 4575);
DISPLAY 0.617021 (750 4575);
PAINT SKYBLUE (750 4575);
FORCEPROP 1 LAST LOCATION C7E3
J 0
(750 4875);
DISPLAY 0.617021 (750 4875);
PAINT AQUA (750 4875);
FORCEPROP 1 LAST VALUE 0.1UF
J 0
(750 4825);
DISPLAY 0.617021 (750 4825);
PAINT SKYBLUE (750 4825);
FORCEPROP 1 LAST VOLTAGE 16V
J 0
(750 4775);
DISPLAY 0.617021 (750 4775);
PAINT SKYBLUE (750 4775);
FORCEPROP 1 LAST PART_NUMBER A36096-030
J 0
(750 4625);
DISPLAY 0.617021 (750 4625);
PAINT BLUE (750 4625);
FORCEPROP 1 LAST TOLERANCE 10%
J 0
(750 4725);
DISPLAY 0.617021 (750 4725);
PAINT SKYBLUE (750 4725);
FORCEPROP 2 LAST SEC 1
J 0
(750 4975);
DISPLAY 0.680851 (750 4975);
PAINT MONO (750 4975);
DISPLAY INVISIBLE (750 4975);
FORCEPROP 2 LAST SEC_TYPE 0402V
J 0
(750 4975);
DISPLAY 1.021277 (750 4975);
PAINT ORANGE (750 4975);
DISPLAY INVISIBLE (750 4975);
FORCEPROP 2 LAST CDS_SEC 1
J 0
(750 4925);
PAINT ORANGE (750 4925);
DISPLAY INVISIBLE (750 4925);
FORCEPROP 2 LAST CDS_LIB dev_discrete
J 0
(700 4775);
PAINT ORANGE (700 4775);
DISPLAY INVISIBLE (700 4775);
FORCEPROP 2 LAST BOM_COST PROC_SIDEBAND
J 0
(750 4975);
DISPLAY 1.021277 (750 4975);
PAINT ORANGE (750 4975);
DISPLAY INVISIBLE (750 4975);
FORCEPROP 2 LAST CDS_LOCATION C7E3
J 0
(750 4875);
DISPLAY 0.617021 (750 4875);
PAINT AQUA (750 4875);
DISPLAY INVISIBLE (750 4875);
FORCEPROP 2 LAST ROOM PROC_SIDEBAND
J 0
(750 4925);
DISPLAY 1.021277 (750 4925);
PAINT ORANGE (750 4925);
DISPLAY INVISIBLE (750 4925);
FORCEPROP 1 LAST PATH I92
J 0
(750 4925);
DISPLAY 0.978723 (750 4925);
PAINT WHITE (750 4925);
DISPLAY INVISIBLE (750 4925);
FORCEADD GND..1
(700 4525);
FORCEPROP 3 LASTPIN (700 4575) SIG_NAME GND\g
J 0
(710 4585);
DISPLAY 0.659574 (710 4585);
PAINT MONO (710 4585);
DISPLAY INVISIBLE (710 4585);
FORCEPROP 1 LAST HDL_POWER GND
J 0
(700 4675);
DISPLAY 0.872340 (700 4675);
PAINT GREEN (700 4675);
DISPLAY INVISIBLE (700 4675);
FORCEPROP 1 LAST PATH I94
J 0
(775 4525);
DISPLAY 0.872340 (775 4525);
PAINT AQUA (775 4525);
DISPLAY INVISIBLE (775 4525);
FORCEPROP 1 LAST BODY_TYPE PLUMBING
J 0
(655 4482);
DISPLAY 0.340426 (655 4482);
PAINT GREEN (655 4482);
DISPLAY INVISIBLE (655 4482);
FORCEPROP 1 LAST SIZE 1B
J 0
(775 4475);
DISPLAY 0.872340 (775 4475);
PAINT AQUA (775 4475);
DISPLAY INVISIBLE (775 4475);
FORCEPROP 2 LAST CDS_LIB mstr_symbols
J 0
(700 4525);
PAINT ORANGE (700 4525);
DISPLAY INVISIBLE (700 4525);
FORCEPROP 1 LAST VOLTAGE 0.0V
J 0
(655 4482);
DISPLAY 0.340426 (655 4482);
PAINT SKYBLUE (655 4482);
DISPLAY INVISIBLE (655 4482);
FORCEADD P3V3_STBY..1
(700 5000);
FORCEPROP 3 LASTPIN (700 4950) SIG_NAME P3V3_STBY\g
J 0
(710 4960);
DISPLAY 0.659574 (710 4960);
PAINT MONO (710 4960);
DISPLAY INVISIBLE (710 4960);
FORCEPROP 1 LAST HDL_POWER P3V3_STBY
J 0
(400 4875);
DISPLAY 0.872340 (400 4875);
PAINT ORANGE (400 4875);
DISPLAY INVISIBLE (400 4875);
FORCEPROP 1 LAST PATH I98
J 0
(745 5002);
DISPLAY 0.340426 (745 5002);
PAINT GREEN (745 5002);
DISPLAY INVISIBLE (745 5002);
FORCEPROP 1 LAST BODY_TYPE PLUMBING
J 0
(655 4957);
DISPLAY 0.340426 (655 4957);
PAINT GREEN (655 4957);
DISPLAY INVISIBLE (655 4957);
FORCEPROP 1 LAST SIZE 1B
J 0
(745 5022);
DISPLAY 0.340426 (745 5022);
PAINT GREEN (745 5022);
DISPLAY INVISIBLE (745 5022);
FORCEPROP 2 LAST CDS_LIB mstr_symbols
J 0
(700 5000);
PAINT ORANGE (700 5000);
DISPLAY INVISIBLE (700 5000);
FORCEPROP 1 LAST VOLTAGE 3.3V
J 0
(655 4957);
DISPLAY 0.340426 (655 4957);
PAINT SKYBLUE (655 4957);
DISPLAY INVISIBLE (655 4957);
FORCEADD CAD_NOTE..1
(1225 4825);
FORCEPROP 0 LAST L2 U7E2
J 0
(1075 4625);
DISPLAY 1.021277 (1075 4625);
PAINT ORANGE (1075 4625);
FORCEPROP 0 LAST L1 PLACE CAP CLOSE TO
J 0
(1075 4675);
DISPLAY 1.021277 (1075 4675);
PAINT ORANGE (1075 4675);
FORCEPROP 1 LAST COMMENT_BODY TRUE
J 0
(1250 4925);
DISPLAY 0.978723 (1250 4925);
PAINT ORANGE (1250 4925);
DISPLAY INVISIBLE (1250 4925);
FORCEPROP 2 LAST CDS_LIB mstr_symbols
J 0
(1225 4825);
PAINT ORANGE (1225 4825);
DISPLAY INVISIBLE (1225 4825);
FORCEADD INTEL_CORP_BPAGE..1
(4250 200);
FORCEPROP 1 LAST CDS_CON_LAST_MODIFIED Fri Jun 16 17:48:35 2017
J 0
(2825 525);
PAINT ORANGE (2825 525);
DISPLAY INVISIBLE (2825 525);
FORCEPROP 1 LAST CUSTOM_TXT_CDS <CURRENT_DESIGN_SHEET> OF <TOTAL_DESIGN_SHEETS>
J 0
(3750 225);
PAINT ORANGE (3750 225);
FORCEPROP 1 LAST CUSTOM_TXT_CDS <CON_LAST_MODIFIED>
J 0
(250 300);
PAINT ORANGE (250 300);
FORCEPROP 2 LAST CUSTOM_TXT_CDS <XR_PAGE_TITLE>
J 0
(-3640 5450);
DISPLAY 0.638298 (-3640 5450);
PAINT PINK (-3640 5450);
DISPLAY INVISIBLE (-3640 5450);
FORCEPROP 1 LAST SCH_TITLE CPU SIDE BAND: PROCHOT & MEMHOT (2/2)
J 0
(-3700 250);
DISPLAY 1.212766 (-3700 250);
PAINT ORANGE (-3700 250);
FORCEPROP 1 LAST COMMENT_BODY TRUE
J 0
(4262 212);
DISPLAY 0.468085 (4262 212);
PAINT GREEN (4262 212);
DISPLAY INVISIBLE (4262 212);
FORCEPROP 2 LAST PAGE_BORDER TRUE
J 0
(-3640 5450);
DISPLAY 0.638298 (-3640 5450);
PAINT PINK (-3640 5450);
DISPLAY INVISIBLE (-3640 5450);
FORCEPROP 2 LAST CDS_LIB mstr_symbols
J 0
(4250 200);
PAINT MONO (4250 200);
DISPLAY INVISIBLE (4250 200);
FORCEPROP 2 LAST CDS_XR_PAGE_TITLE CR-95 : @BASEBOARD_FAB2_LIB.BASEBOARD_FAB2(SCH_1):PAGE95
J 0
(-3640 5450);
DISPLAY 0.638298 (-3640 5450);
PAINT PINK (-3640 5450);
DISPLAY INVISIBLE (-3640 5450);
FORCEADD CAD_NOTE..1
(1575 3550);
FORCEPROP 0 LAST L1 PLACE CAP CLOSE TO
J 0
(1425 3400);
DISPLAY 1.021277 (1425 3400);
PAINT ORANGE (1425 3400);
FORCEPROP 0 LAST L2 U7E3
J 0
(1425 3350);
DISPLAY 1.021277 (1425 3350);
PAINT ORANGE (1425 3350);
FORCEPROP 1 LAST COMMENT_BODY TRUE
J 0
(1600 3650);
DISPLAY 0.978723 (1600 3650);
PAINT ORANGE (1600 3650);
DISPLAY INVISIBLE (1600 3650);
FORCEPROP 2 LAST CDS_LIB mstr_symbols
J 0
(1575 3550);
PAINT ORANGE (1575 3550);
DISPLAY INVISIBLE (1575 3550);
WIRE 16 -1 (-3100 500)(-3100 475);
WIRE 16 -1 (2150 1150)(2150 1000);
WIRE 16 -1 (2150 1900)(2150 2025);
WIRE 16 -1 (1125 3625)(1125 3550);
WIRE 16 -1 (1125 3350)(1125 3250);
WIRE 16 -1 (-3100 4300)(-3100 4350);
WIRE 16 -1 (-3100 3750)(-3100 3725);
WIRE 16 -1 (-3100 3075)(-3100 3050);
WIRE 16 -1 (-3100 2425)(-3100 2400);
WIRE 16 -1 (-3100 1750)(-3100 1725);
WIRE 16 -1 (-3100 1100)(-3100 1075);
WIRE 16 -1 (3050 4275)(3050 4525);
WIRE 16 -1 (2475 5000)(2475 4900);
WIRE 16 -1 (2475 4125)(2475 4075);
WIRE 16 -1 (3225 3050)(3225 2875);
WIRE 16 -1 (2550 3550)(2550 3475);
WIRE 16 -1 (2550 2675)(2550 2625);
WIRE 16 -1 (700 4675)(700 4575);
WIRE 16 -1 (700 4950)(700 4875);
WIRE 16 2175 (0 575)(0 5125);
WIRE 16 -1 (-3425 600)(-3300 600);
WIRE 16 -1 (-3425 600)(-3425 1200);
WIRE 16 -1 (-3300 1200)(-3425 1200);
WIRE 16 -1 (-3425 1850)(-3425 1200);
WIRE 16 -1 (-3300 1850)(-3425 1850);
WIRE 16 -1 (-3425 1850)(-3425 2525);
WIRE 16 -1 (-3425 2525)(-3300 2525);
WIRE 16 -1 (-3425 2525)(-3425 3175);
WIRE 16 -1 (-3425 3175)(-3300 3175);
WIRE 16 -1 (-3425 5025)(-2525 5025);
FORCEPROP 2 LAST SIG_NAME FM_SYS_THROTTLE_LVC3
J 0
(-3110 5035);
DISPLAY 0.617021 (-3110 5035);
PAINT ORANGE (-3110 5035);
WIRE 16 -1 (-3425 3175)(-3425 3850);
WIRE 16 -1 (-3300 3850)(-3425 3850);
WIRE 16 -1 (-3425 3850)(-3425 4450);
WIRE 16 -1 (-3425 4450)(-3425 5025);
WIRE 16 -1 (-3300 4450)(-3425 4450);
WIRE 16 682 (4050 3875)(125 3875);
WIRE 16 682 (4075 2350)(100 2350);
WIRE 16 -1 (-3100 4850)(-750 4850);
FORCEPROP 0 LAST SIG_NAME FM_PWRBRK_N
J 0
(-1285 4860);
DISPLAY 0.617021 (-1285 4860);
PAINT ORANGE (-1285 4860);
WIRE 16 -1 (-3100 4750)(-3100 4850);
WIRE 16 -1 (-3100 4200)(-3100 4150);
WIRE 16 -1 (-750 4200)(-3100 4200);
FORCEPROP 2 LAST SIG_NAME H_CPU0_PROCHOT_G_N
J 0
(-1300 4210);
DISPLAY 0.617021 (-1300 4210);
PAINT ORANGE (-1300 4210);
WIRE 16 -1 (1950 1250)(1425 1250);
FORCEPROP 0 LAST SIG_NAME FM_THROTTLE_R_N
J 0
(1465 1260);
DISPLAY 0.617021 (1465 1260);
PAINT ORANGE (1465 1260);
FORCEPROP 2 LASTPROP $XRERR UNIQUE?
J 0
(1225 1260);
DISPLAY 0.638298 (1225 1260);
PAINT MONO (1225 1260);
DISPLAY INVISIBLE (1225 1260);
WIRE 16 -1 (1225 1250)(750 1250);
FORCEPROP 0 LAST SIG_NAME FM_THROTTLE_N
J 0
(765 1260);
DISPLAY 0.617021 (765 1260);
PAINT ORANGE (765 1260);
WIRE 16 -1 (2150 1700)(2150 1600);
WIRE 16 -1 (2150 1600)(2150 1550);
WIRE 16 -1 (2150 1600)(3205 1600);
FORCEPROP 2 LAST SIG_NAME FM_SYS_THROTTLE_LVC3
J 0
(2590 1610);
DISPLAY 0.617021 (2590 1610);
PAINT ORANGE (2590 1610);
WIRE 16 -1 (2350 2775)(1725 2775);
FORCEPROP 0 LAST SIG_NAME IRQ_CPU1_PROCHOT_G_N
J 0
(1765 2785);
DISPLAY 0.617021 (1765 2785);
PAINT ORANGE (1765 2785);
FORCEPROP 2 LASTPROP $XRERR UNIQUE?
J 0
(1525 2785);
DISPLAY 0.638298 (1525 2785);
PAINT MONO (1525 2785);
DISPLAY INVISIBLE (1525 2785);
WIRE 16 -1 (3225 3450)(3225 3575);
WIRE 16 -1 (3705 3575)(3225 3575);
FORCEPROP 0 LAST SIG_NAME H_CPU1_PROCHOT_G_N
J 0
(3225 3585);
DISPLAY 0.617021 (3225 3585);
PAINT ORANGE (3225 3585);
WIRE 16 -1 (2275 4225)(1700 4225);
FORCEPROP 0 LAST SIG_NAME IRQ_CPU0_PROCHOT_G_N
J 0
(1740 4235);
DISPLAY 0.617021 (1740 4235);
PAINT ORANGE (1740 4235);
FORCEPROP 2 LASTPROP $XRERR UNIQUE?
J 0
(1500 4235);
DISPLAY 0.638298 (1500 4235);
PAINT MONO (1500 4235);
DISPLAY INVISIBLE (1500 4235);
WIRE 16 -1 (550 4275)(1400 4275);
FORCEPROP 0 LAST SIG_NAME FM_PVCCIN_CPU0_PWR_IN_ALERT_N
J 0
(525 4290);
DISPLAY 0.617021 (525 4290);
PAINT ORANGE (525 4290);
WIRE 16 -1 (2475 4525)(2475 4625);
WIRE 16 -1 (2850 4625)(2475 4625);
FORCEPROP 0 LAST SIG_NAME IRQ_CPU0_VRHOT
J 0
(2515 4635);
DISPLAY 0.617021 (2515 4635);
PAINT ORANGE (2515 4635);
FORCEPROP 2 LASTPROP $XRERR UNIQUE?
J 0
(2275 4635);
DISPLAY 0.638298 (2275 4635);
PAINT MONO (2275 4635);
DISPLAY INVISIBLE (2275 4635);
WIRE 16 -1 (2475 4700)(2475 4625);
WIRE 16 -1 (2550 3275)(2550 3150);
WIRE 16 -1 (3025 3150)(2550 3150);
FORCEPROP 0 LAST SIG_NAME IRQ_CPU1_VRHOT
J 0
(2615 3160);
DISPLAY 0.617021 (2615 3160);
PAINT ORANGE (2615 3160);
FORCEPROP 2 LASTPROP $XRERR UNIQUE?
J 0
(2375 3160);
DISPLAY 0.638298 (2375 3160);
PAINT MONO (2375 3160);
DISPLAY INVISIBLE (2375 3160);
WIRE 16 -1 (2550 3075)(2550 3150);
WIRE 16 -1 (-3100 3475)(-3100 3525);
WIRE 16 -1 (-750 3525)(-3100 3525);
FORCEPROP 2 LAST SIG_NAME H_CPU1_PROCHOT_G_N
J 0
(-1300 3535);
DISPLAY 0.617021 (-1300 3535);
PAINT ORANGE (-1300 3535);
WIRE 16 -1 (-3100 2825)(-3100 2850);
WIRE 16 -1 (-3100 2850)(-750 2850);
FORCEPROP 2 LAST SIG_NAME H_CPU0_MEMABC_MEMHOT_G_N
J 0
(-1450 2860);
DISPLAY 0.617021 (-1450 2860);
PAINT ORANGE (-1450 2860);
WIRE 16 -1 (600 2725)(1425 2725);
FORCEPROP 0 LAST SIG_NAME IRQ_PVCCIN_CPU1_VRHOT_LVC3_N
J 0
(575 2735);
DISPLAY 0.617021 (575 2735);
PAINT ORANGE (575 2735);
WIRE 16 -1 (-3100 2200)(-3100 2150);
WIRE 16 -1 (-3100 2200)(-725 2200);
FORCEPROP 2 LAST SIG_NAME H_CPU0_MEMDEF_MEMHOT_G_N
J 0
(-1425 2210);
DISPLAY 0.617021 (-1425 2210);
PAINT ORANGE (-1425 2210);
WIRE 16 -1 (-3100 1500)(-3100 1550);
WIRE 16 -1 (-3100 1550)(-725 1550);
FORCEPROP 2 LAST SIG_NAME H_CPU1_MEMGHJ_MEMHOT_G_N
J 0
(-1450 1560);
DISPLAY 0.617021 (-1450 1560);
PAINT ORANGE (-1450 1560);
WIRE 16 -1 (-3100 900)(-3100 925);
WIRE 16 -1 (-3100 925)(-725 925);
FORCEPROP 2 LAST SIG_NAME H_CPU1_MEMKLM_MEMHOT_G_N
J 0
(-1425 935);
DISPLAY 0.617021 (-1425 935);
PAINT ORANGE (-1425 935);
WIRE 16 -1 (600 2825)(1425 2825);
FORCEPROP 0 LAST SIG_NAME FM_PVCCIN_CPU1_PWR_IN_ALERT_N
J 0
(575 2840);
DISPLAY 0.617021 (575 2840);
PAINT ORANGE (575 2840);
WIRE 16 -1 (550 4175)(1400 4175);
FORCEPROP 0 LAST SIG_NAME IRQ_PVCCIN_CPU0_VRHOT_LVC3_N
J 0
(525 4185);
DISPLAY 0.617021 (525 4185);
PAINT ORANGE (525 4185);
WIRE 16 -1 (3050 4925)(3050 5025);
WIRE 16 -1 (3605 5025)(3050 5025);
FORCEPROP 0 LAST SIG_NAME H_CPU0_PROCHOT_G_N
J 0
(3050 5035);
DISPLAY 0.617021 (3050 5035);
PAINT ORANGE (3050 5035);
DOT 1 (-3425 4450);
DOT 1 (-3425 1200);
DOT 1 (-3425 1850);
DOT 1 (-3425 2525);
DOT 1 (-3425 3175);
DOT 1 (-3425 3850);
DOT 1 (2475 4625);
DOT 1 (2150 1600);
DOT 1 (2550 3150);
FORCENOTE
ROOM=PROC_SIDEBAND
(-2812 358) 0;
DISPLAY LEFT (-2812 358);
DISPLAY 1.595745 (-2812 358);
PAINT PURPLE (-2812 358);
QUIT
